FILE_TYPE = MACRO_DRAWING;
SET COLOR_WIRE YELLOW;
SET COLOR_PROP ORANGE;
SET COLOR_DOT WHITE;
SET COLOR_ARC YELLOW;
SET COLOR_BODY GREEN;
SET COLOR_NOTE PURPLE;
SET PROP_DISPLAY VALUE;
SET PAGE_NUMBER P72;
FORCEADD Q_CAP..1
(-9400 1325);
FORCEPROP 1 LAST LOCATION C2298
J 0
(-9350 1425);
DISPLAY 0.489362 (-9350 1425);
PAINT SKYBLUE (-9350 1425);
FORCEPROP 2 LAST $SEC 1
J 0
(-9350 1525);
DISPLAY 0.680851 (-9350 1525);
PAINT MONO (-9350 1525);
DISPLAY INVISIBLE (-9350 1525);
FORCEPROP 2 LAST CDS_SEC 1
J 0
(-9350 1525);
DISPLAY 1.021277 (-9350 1525);
DISPLAY INVISIBLE (-9350 1525);
FORCEPROP 1 LASTPIN (-9400 1425) $PN 1
J 0
(-9390 1405);
DISPLAY 0.489362 (-9390 1405);
FORCEPROP 1 LASTPIN (-9400 1225) $PN 2
J 0
(-9390 1205);
DISPLAY 0.489362 (-9390 1205);
FORCEPROP 1 LAST MATERIAL X6S
J 0
(-9350 1225);
DISPLAY 0.489362 (-9350 1225);
PAINT SKYBLUE (-9350 1225);
FORCEPROP 1 LAST TOLERANCE 20%
J 0
(-9350 1275);
DISPLAY 0.489362 (-9350 1275);
PAINT SKYBLUE (-9350 1275);
FORCEPROP 1 LAST VALUE 22UF
J 0
(-9350 1375);
DISPLAY 0.489362 (-9350 1375);
PAINT SKYBLUE (-9350 1375);
FORCEPROP 1 LAST VOLTAGE 4V
J 0
(-9350 1325);
DISPLAY 0.489362 (-9350 1325);
PAINT SKYBLUE (-9350 1325);
FORCEPROP 1 LAST PACK_TYPE C0402
J 0
(-9350 1125);
DISPLAY 0.489362 (-9350 1125);
PAINT SKYBLUE (-9350 1125);
FORCEPROP 2 LAST CDS_LIB pure_quanta
J 0
(-9400 1325);
PAINT MONO (-9400 1325);
DISPLAY INVISIBLE (-9400 1325);
FORCEPROP 1 LAST PATH I1
J 0
(-9350 1475);
DISPLAY 0.978723 (-9350 1475);
PAINT WHITE (-9350 1475);
DISPLAY INVISIBLE (-9350 1475);
FORCEPROP 1 LAST PART_NUMBER CH622KMEB02
J 0
(-9350 1175);
DISPLAY 0.489362 (-9350 1175);
PAINT SKYBLUE (-9350 1175);
DISPLAY INVISIBLE (-9350 1175);
FORCEADD Q_CAP..1
(-8950 2125);
FORCEPROP 1 LAST LOCATION C2303
J 0
(-8900 2225);
DISPLAY 0.489362 (-8900 2225);
PAINT SKYBLUE (-8900 2225);
FORCEPROP 2 LAST $SEC 1
J 0
(-8900 2325);
DISPLAY 0.680851 (-8900 2325);
PAINT MONO (-8900 2325);
DISPLAY INVISIBLE (-8900 2325);
FORCEPROP 2 LAST CDS_SEC 1
J 0
(-8900 2325);
DISPLAY 1.021277 (-8900 2325);
DISPLAY INVISIBLE (-8900 2325);
FORCEPROP 1 LASTPIN (-8950 2225) $PN 1
J 0
(-8940 2205);
DISPLAY 0.489362 (-8940 2205);
FORCEPROP 1 LASTPIN (-8950 2025) $PN 2
J 0
(-8940 2005);
DISPLAY 0.489362 (-8940 2005);
FORCEPROP 1 LAST MATERIAL X6S
J 0
(-8900 2025);
DISPLAY 0.489362 (-8900 2025);
PAINT SKYBLUE (-8900 2025);
FORCEPROP 1 LAST TOLERANCE 20%
J 0
(-8900 2075);
DISPLAY 0.489362 (-8900 2075);
PAINT SKYBLUE (-8900 2075);
FORCEPROP 1 LAST VALUE 22UF
J 0
(-8900 2175);
DISPLAY 0.489362 (-8900 2175);
PAINT SKYBLUE (-8900 2175);
FORCEPROP 1 LAST VOLTAGE 4V
J 0
(-8900 2125);
DISPLAY 0.489362 (-8900 2125);
PAINT SKYBLUE (-8900 2125);
FORCEPROP 1 LAST PACK_TYPE C0402
J 0
(-8900 1925);
DISPLAY 0.489362 (-8900 1925);
PAINT SKYBLUE (-8900 1925);
FORCEPROP 2 LAST CDS_LIB pure_quanta
J 0
(-8950 2125);
PAINT MONO (-8950 2125);
DISPLAY INVISIBLE (-8950 2125);
FORCEPROP 1 LAST PATH I10
J 0
(-8900 2275);
DISPLAY 0.978723 (-8900 2275);
PAINT WHITE (-8900 2275);
DISPLAY INVISIBLE (-8900 2275);
FORCEPROP 1 LAST PART_NUMBER CH622KMEB02
J 0
(-8900 1975);
DISPLAY 0.489362 (-8900 1975);
PAINT SKYBLUE (-8900 1975);
DISPLAY INVISIBLE (-8900 1975);
FORCEADD Q_CAP..1
(-825 3725);
FORCEPROP 1 LAST LOCATION C2403
J 0
(-775 3825);
DISPLAY 0.489362 (-775 3825);
PAINT SKYBLUE (-775 3825);
FORCEPROP 2 LAST $SEC 1
J 0
(-775 3925);
DISPLAY 0.680851 (-775 3925);
PAINT MONO (-775 3925);
DISPLAY INVISIBLE (-775 3925);
FORCEPROP 2 LAST CDS_SEC 1
J 0
(-775 3925);
DISPLAY 1.021277 (-775 3925);
DISPLAY INVISIBLE (-775 3925);
FORCEPROP 1 LASTPIN (-825 3825) $PN 1
J 0
(-815 3805);
DISPLAY 0.489362 (-815 3805);
FORCEPROP 1 LASTPIN (-825 3625) $PN 2
J 0
(-815 3605);
DISPLAY 0.489362 (-815 3605);
FORCEPROP 1 LAST MATERIAL X6S
J 0
(-775 3625);
DISPLAY 0.489362 (-775 3625);
PAINT SKYBLUE (-775 3625);
FORCEPROP 1 LAST TOLERANCE 20%
J 0
(-775 3675);
DISPLAY 0.489362 (-775 3675);
PAINT SKYBLUE (-775 3675);
FORCEPROP 1 LAST VALUE 22UF
J 0
(-775 3775);
DISPLAY 0.489362 (-775 3775);
PAINT SKYBLUE (-775 3775);
FORCEPROP 1 LAST VOLTAGE 4V
J 0
(-775 3725);
DISPLAY 0.489362 (-775 3725);
PAINT SKYBLUE (-775 3725);
FORCEPROP 1 LAST PACK_TYPE C0402
J 0
(-775 3525);
DISPLAY 0.489362 (-775 3525);
PAINT SKYBLUE (-775 3525);
FORCEPROP 2 LAST CDS_LIB pure_quanta
J 0
(-825 3725);
PAINT MONO (-825 3725);
DISPLAY INVISIBLE (-825 3725);
FORCEPROP 1 LAST PATH I100
J 0
(-775 3875);
DISPLAY 0.978723 (-775 3875);
PAINT WHITE (-775 3875);
DISPLAY INVISIBLE (-775 3875);
FORCEPROP 1 LAST PART_NUMBER CH622KMEB02
J 0
(-775 3575);
DISPLAY 0.489362 (-775 3575);
PAINT SKYBLUE (-775 3575);
DISPLAY INVISIBLE (-775 3575);
FORCEADD Q_CAP..1
(-3925 4500);
FORCEPROP 1 LAST LOCATION C2362
J 0
(-3875 4600);
DISPLAY 0.489362 (-3875 4600);
PAINT SKYBLUE (-3875 4600);
FORCEPROP 2 LAST $SEC 1
J 0
(-3875 4700);
DISPLAY 0.680851 (-3875 4700);
PAINT MONO (-3875 4700);
DISPLAY INVISIBLE (-3875 4700);
FORCEPROP 2 LAST CDS_SEC 1
J 0
(-3875 4700);
DISPLAY 1.021277 (-3875 4700);
DISPLAY INVISIBLE (-3875 4700);
FORCEPROP 1 LASTPIN (-3925 4600) $PN 1
J 0
(-3915 4580);
DISPLAY 0.489362 (-3915 4580);
FORCEPROP 1 LASTPIN (-3925 4400) $PN 2
J 0
(-3915 4380);
DISPLAY 0.489362 (-3915 4380);
FORCEPROP 1 LAST MATERIAL X6S
J 0
(-3875 4400);
DISPLAY 0.489362 (-3875 4400);
PAINT SKYBLUE (-3875 4400);
FORCEPROP 1 LAST TOLERANCE 20%
J 0
(-3875 4450);
DISPLAY 0.489362 (-3875 4450);
PAINT SKYBLUE (-3875 4450);
FORCEPROP 1 LAST VALUE 22UF
J 0
(-3875 4550);
DISPLAY 0.489362 (-3875 4550);
PAINT SKYBLUE (-3875 4550);
FORCEPROP 1 LAST VOLTAGE 4V
J 0
(-3875 4500);
DISPLAY 0.489362 (-3875 4500);
PAINT SKYBLUE (-3875 4500);
FORCEPROP 1 LAST PACK_TYPE C0402
J 0
(-3875 4300);
DISPLAY 0.489362 (-3875 4300);
PAINT SKYBLUE (-3875 4300);
FORCEPROP 2 LAST CDS_LIB pure_quanta
J 0
(-3925 4500);
PAINT MONO (-3925 4500);
DISPLAY INVISIBLE (-3925 4500);
FORCEPROP 1 LAST PATH I101
J 0
(-3875 4650);
DISPLAY 0.978723 (-3875 4650);
PAINT WHITE (-3875 4650);
DISPLAY INVISIBLE (-3875 4650);
FORCEPROP 1 LAST PART_NUMBER CH622KMEB02
J 0
(-3875 4350);
DISPLAY 0.489362 (-3875 4350);
PAINT SKYBLUE (-3875 4350);
DISPLAY INVISIBLE (-3875 4350);
FORCEADD Q_CAP..1
(-3475 4500);
FORCEPROP 1 LAST LOCATION C2368
J 0
(-3425 4600);
DISPLAY 0.489362 (-3425 4600);
PAINT SKYBLUE (-3425 4600);
FORCEPROP 2 LAST $SEC 1
J 0
(-3425 4700);
DISPLAY 0.680851 (-3425 4700);
PAINT MONO (-3425 4700);
DISPLAY INVISIBLE (-3425 4700);
FORCEPROP 2 LAST CDS_SEC 1
J 0
(-3425 4700);
DISPLAY 1.021277 (-3425 4700);
DISPLAY INVISIBLE (-3425 4700);
FORCEPROP 1 LASTPIN (-3475 4600) $PN 1
J 0
(-3465 4580);
DISPLAY 0.489362 (-3465 4580);
FORCEPROP 1 LASTPIN (-3475 4400) $PN 2
J 0
(-3465 4380);
DISPLAY 0.489362 (-3465 4380);
FORCEPROP 1 LAST MATERIAL X6S
J 0
(-3425 4400);
DISPLAY 0.489362 (-3425 4400);
PAINT SKYBLUE (-3425 4400);
FORCEPROP 1 LAST TOLERANCE 20%
J 0
(-3425 4450);
DISPLAY 0.489362 (-3425 4450);
PAINT SKYBLUE (-3425 4450);
FORCEPROP 1 LAST VALUE 22UF
J 0
(-3425 4550);
DISPLAY 0.489362 (-3425 4550);
PAINT SKYBLUE (-3425 4550);
FORCEPROP 1 LAST VOLTAGE 4V
J 0
(-3425 4500);
DISPLAY 0.489362 (-3425 4500);
PAINT SKYBLUE (-3425 4500);
FORCEPROP 1 LAST PACK_TYPE C0402
J 0
(-3425 4300);
DISPLAY 0.489362 (-3425 4300);
PAINT SKYBLUE (-3425 4300);
FORCEPROP 2 LAST CDS_LIB pure_quanta
J 0
(-3475 4500);
PAINT MONO (-3475 4500);
DISPLAY INVISIBLE (-3475 4500);
FORCEPROP 1 LAST PATH I102
J 0
(-3425 4650);
DISPLAY 0.978723 (-3425 4650);
PAINT WHITE (-3425 4650);
DISPLAY INVISIBLE (-3425 4650);
FORCEPROP 1 LAST PART_NUMBER CH622KMEB02
J 0
(-3425 4350);
DISPLAY 0.489362 (-3425 4350);
PAINT SKYBLUE (-3425 4350);
DISPLAY INVISIBLE (-3425 4350);
FORCEADD Q_CAP..1
(-3025 4500);
FORCEPROP 1 LAST LOCATION C2374
J 0
(-2975 4600);
DISPLAY 0.489362 (-2975 4600);
PAINT SKYBLUE (-2975 4600);
FORCEPROP 2 LAST $SEC 1
J 0
(-2975 4700);
DISPLAY 0.680851 (-2975 4700);
PAINT MONO (-2975 4700);
DISPLAY INVISIBLE (-2975 4700);
FORCEPROP 2 LAST CDS_SEC 1
J 0
(-2975 4700);
DISPLAY 1.021277 (-2975 4700);
DISPLAY INVISIBLE (-2975 4700);
FORCEPROP 1 LASTPIN (-3025 4600) $PN 1
J 0
(-3015 4580);
DISPLAY 0.489362 (-3015 4580);
FORCEPROP 1 LASTPIN (-3025 4400) $PN 2
J 0
(-3015 4380);
DISPLAY 0.489362 (-3015 4380);
FORCEPROP 1 LAST MATERIAL X6S
J 0
(-2975 4400);
DISPLAY 0.489362 (-2975 4400);
PAINT SKYBLUE (-2975 4400);
FORCEPROP 1 LAST TOLERANCE 20%
J 0
(-2975 4450);
DISPLAY 0.489362 (-2975 4450);
PAINT SKYBLUE (-2975 4450);
FORCEPROP 1 LAST VALUE 22UF
J 0
(-2975 4550);
DISPLAY 0.489362 (-2975 4550);
PAINT SKYBLUE (-2975 4550);
FORCEPROP 1 LAST VOLTAGE 4V
J 0
(-2975 4500);
DISPLAY 0.489362 (-2975 4500);
PAINT SKYBLUE (-2975 4500);
FORCEPROP 1 LAST PACK_TYPE C0402
J 0
(-2975 4300);
DISPLAY 0.489362 (-2975 4300);
PAINT SKYBLUE (-2975 4300);
FORCEPROP 2 LAST CDS_LIB pure_quanta
J 0
(-3025 4500);
PAINT MONO (-3025 4500);
DISPLAY INVISIBLE (-3025 4500);
FORCEPROP 1 LAST PATH I103
J 0
(-2975 4650);
DISPLAY 0.978723 (-2975 4650);
PAINT WHITE (-2975 4650);
DISPLAY INVISIBLE (-2975 4650);
FORCEPROP 1 LAST PART_NUMBER CH622KMEB02
J 0
(-2975 4350);
DISPLAY 0.489362 (-2975 4350);
PAINT SKYBLUE (-2975 4350);
DISPLAY INVISIBLE (-2975 4350);
FORCEADD Q_CAP..1
(-2575 4500);
FORCEPROP 1 LAST LOCATION C2380
J 0
(-2525 4600);
DISPLAY 0.489362 (-2525 4600);
PAINT SKYBLUE (-2525 4600);
FORCEPROP 2 LAST $SEC 1
J 0
(-2525 4700);
DISPLAY 0.680851 (-2525 4700);
PAINT MONO (-2525 4700);
DISPLAY INVISIBLE (-2525 4700);
FORCEPROP 2 LAST CDS_SEC 1
J 0
(-2525 4700);
DISPLAY 1.021277 (-2525 4700);
DISPLAY INVISIBLE (-2525 4700);
FORCEPROP 1 LASTPIN (-2575 4600) $PN 1
J 0
(-2565 4580);
DISPLAY 0.489362 (-2565 4580);
FORCEPROP 1 LASTPIN (-2575 4400) $PN 2
J 0
(-2565 4380);
DISPLAY 0.489362 (-2565 4380);
FORCEPROP 1 LAST MATERIAL X6S
J 0
(-2525 4400);
DISPLAY 0.489362 (-2525 4400);
PAINT SKYBLUE (-2525 4400);
FORCEPROP 1 LAST TOLERANCE 20%
J 0
(-2525 4450);
DISPLAY 0.489362 (-2525 4450);
PAINT SKYBLUE (-2525 4450);
FORCEPROP 1 LAST VALUE 22UF
J 0
(-2525 4550);
DISPLAY 0.489362 (-2525 4550);
PAINT SKYBLUE (-2525 4550);
FORCEPROP 1 LAST VOLTAGE 4V
J 0
(-2525 4500);
DISPLAY 0.489362 (-2525 4500);
PAINT SKYBLUE (-2525 4500);
FORCEPROP 1 LAST PACK_TYPE C0402
J 0
(-2525 4300);
DISPLAY 0.489362 (-2525 4300);
PAINT SKYBLUE (-2525 4300);
FORCEPROP 2 LAST CDS_LIB pure_quanta
J 0
(-2575 4500);
PAINT MONO (-2575 4500);
DISPLAY INVISIBLE (-2575 4500);
FORCEPROP 1 LAST PATH I104
J 0
(-2525 4650);
DISPLAY 0.978723 (-2525 4650);
PAINT WHITE (-2525 4650);
DISPLAY INVISIBLE (-2525 4650);
FORCEPROP 1 LAST PART_NUMBER CH622KMEB02
J 0
(-2525 4350);
DISPLAY 0.489362 (-2525 4350);
PAINT SKYBLUE (-2525 4350);
DISPLAY INVISIBLE (-2525 4350);
FORCEADD Q_CAP..1
(-2125 4500);
FORCEPROP 1 LAST LOCATION C2386
J 0
(-2075 4600);
DISPLAY 0.489362 (-2075 4600);
PAINT SKYBLUE (-2075 4600);
FORCEPROP 2 LAST $SEC 1
J 0
(-2075 4700);
DISPLAY 0.680851 (-2075 4700);
PAINT MONO (-2075 4700);
DISPLAY INVISIBLE (-2075 4700);
FORCEPROP 2 LAST CDS_SEC 1
J 0
(-2075 4700);
DISPLAY 1.021277 (-2075 4700);
DISPLAY INVISIBLE (-2075 4700);
FORCEPROP 1 LASTPIN (-2125 4600) $PN 1
J 0
(-2115 4580);
DISPLAY 0.489362 (-2115 4580);
FORCEPROP 1 LASTPIN (-2125 4400) $PN 2
J 0
(-2115 4380);
DISPLAY 0.489362 (-2115 4380);
FORCEPROP 1 LAST MATERIAL X6S
J 0
(-2075 4400);
DISPLAY 0.489362 (-2075 4400);
PAINT SKYBLUE (-2075 4400);
FORCEPROP 1 LAST TOLERANCE 20%
J 0
(-2075 4450);
DISPLAY 0.489362 (-2075 4450);
PAINT SKYBLUE (-2075 4450);
FORCEPROP 1 LAST VALUE 22UF
J 0
(-2075 4550);
DISPLAY 0.489362 (-2075 4550);
PAINT SKYBLUE (-2075 4550);
FORCEPROP 1 LAST VOLTAGE 4V
J 0
(-2075 4500);
DISPLAY 0.489362 (-2075 4500);
PAINT SKYBLUE (-2075 4500);
FORCEPROP 1 LAST PACK_TYPE C0402
J 0
(-2075 4300);
DISPLAY 0.489362 (-2075 4300);
PAINT SKYBLUE (-2075 4300);
FORCEPROP 2 LAST CDS_LIB pure_quanta
J 0
(-2125 4500);
PAINT MONO (-2125 4500);
DISPLAY INVISIBLE (-2125 4500);
FORCEPROP 1 LAST PATH I105
J 0
(-2075 4650);
DISPLAY 0.978723 (-2075 4650);
PAINT WHITE (-2075 4650);
DISPLAY INVISIBLE (-2075 4650);
FORCEPROP 1 LAST PART_NUMBER CH622KMEB02
J 0
(-2075 4350);
DISPLAY 0.489362 (-2075 4350);
PAINT SKYBLUE (-2075 4350);
DISPLAY INVISIBLE (-2075 4350);
FORCEADD Q_CAP..1
(-1675 4500);
FORCEPROP 1 LAST LOCATION C2392
J 0
(-1625 4600);
DISPLAY 0.489362 (-1625 4600);
PAINT SKYBLUE (-1625 4600);
FORCEPROP 2 LAST $SEC 1
J 0
(-1625 4700);
DISPLAY 0.680851 (-1625 4700);
PAINT MONO (-1625 4700);
DISPLAY INVISIBLE (-1625 4700);
FORCEPROP 2 LAST CDS_SEC 1
J 0
(-1625 4700);
DISPLAY 1.021277 (-1625 4700);
DISPLAY INVISIBLE (-1625 4700);
FORCEPROP 1 LASTPIN (-1675 4600) $PN 1
J 0
(-1665 4580);
DISPLAY 0.489362 (-1665 4580);
FORCEPROP 1 LASTPIN (-1675 4400) $PN 2
J 0
(-1665 4380);
DISPLAY 0.489362 (-1665 4380);
FORCEPROP 1 LAST MATERIAL X6S
J 0
(-1625 4400);
DISPLAY 0.489362 (-1625 4400);
PAINT SKYBLUE (-1625 4400);
FORCEPROP 1 LAST TOLERANCE 20%
J 0
(-1625 4450);
DISPLAY 0.489362 (-1625 4450);
PAINT SKYBLUE (-1625 4450);
FORCEPROP 1 LAST VALUE 22UF
J 0
(-1625 4550);
DISPLAY 0.489362 (-1625 4550);
PAINT SKYBLUE (-1625 4550);
FORCEPROP 1 LAST VOLTAGE 4V
J 0
(-1625 4500);
DISPLAY 0.489362 (-1625 4500);
PAINT SKYBLUE (-1625 4500);
FORCEPROP 1 LAST PACK_TYPE C0402
J 0
(-1625 4300);
DISPLAY 0.489362 (-1625 4300);
PAINT SKYBLUE (-1625 4300);
FORCEPROP 2 LAST CDS_LIB pure_quanta
J 0
(-1675 4500);
PAINT MONO (-1675 4500);
DISPLAY INVISIBLE (-1675 4500);
FORCEPROP 1 LAST PATH I106
J 0
(-1625 4650);
DISPLAY 0.978723 (-1625 4650);
PAINT WHITE (-1625 4650);
DISPLAY INVISIBLE (-1625 4650);
FORCEPROP 1 LAST PART_NUMBER CH622KMEB02
J 0
(-1625 4350);
DISPLAY 0.489362 (-1625 4350);
PAINT SKYBLUE (-1625 4350);
DISPLAY INVISIBLE (-1625 4350);
FORCEADD Q_CAP..1
(-1225 4500);
FORCEPROP 1 LAST LOCATION C2397
J 0
(-1175 4600);
DISPLAY 0.489362 (-1175 4600);
PAINT SKYBLUE (-1175 4600);
FORCEPROP 2 LAST $SEC 1
J 0
(-1175 4700);
DISPLAY 0.680851 (-1175 4700);
PAINT MONO (-1175 4700);
DISPLAY INVISIBLE (-1175 4700);
FORCEPROP 2 LAST CDS_SEC 1
J 0
(-1175 4700);
DISPLAY 1.021277 (-1175 4700);
DISPLAY INVISIBLE (-1175 4700);
FORCEPROP 1 LASTPIN (-1225 4600) $PN 1
J 0
(-1215 4580);
DISPLAY 0.489362 (-1215 4580);
FORCEPROP 1 LASTPIN (-1225 4400) $PN 2
J 0
(-1215 4380);
DISPLAY 0.489362 (-1215 4380);
FORCEPROP 1 LAST MATERIAL X6S
J 0
(-1175 4400);
DISPLAY 0.489362 (-1175 4400);
PAINT SKYBLUE (-1175 4400);
FORCEPROP 1 LAST TOLERANCE 20%
J 0
(-1175 4450);
DISPLAY 0.489362 (-1175 4450);
PAINT SKYBLUE (-1175 4450);
FORCEPROP 1 LAST VALUE 22UF
J 0
(-1175 4550);
DISPLAY 0.489362 (-1175 4550);
PAINT SKYBLUE (-1175 4550);
FORCEPROP 1 LAST VOLTAGE 4V
J 0
(-1175 4500);
DISPLAY 0.489362 (-1175 4500);
PAINT SKYBLUE (-1175 4500);
FORCEPROP 1 LAST PACK_TYPE C0402
J 0
(-1175 4300);
DISPLAY 0.489362 (-1175 4300);
PAINT SKYBLUE (-1175 4300);
FORCEPROP 2 LAST CDS_LIB pure_quanta
J 0
(-1225 4500);
PAINT MONO (-1225 4500);
DISPLAY INVISIBLE (-1225 4500);
FORCEPROP 1 LAST PATH I107
J 0
(-1175 4650);
DISPLAY 0.978723 (-1175 4650);
PAINT WHITE (-1175 4650);
DISPLAY INVISIBLE (-1175 4650);
FORCEPROP 1 LAST PART_NUMBER CH622KMEB02
J 0
(-1175 4350);
DISPLAY 0.489362 (-1175 4350);
PAINT SKYBLUE (-1175 4350);
DISPLAY INVISIBLE (-1175 4350);
FORCEADD UNIVERSAL_GND..1
(-825 4125);
FORCEPROP 3 LASTPIN (-825 4175) SIG_NAME GND\g
J 0
(-815 4185);
DISPLAY 0.659574 (-815 4185);
PAINT MONO (-815 4185);
DISPLAY INVISIBLE (-815 4185);
FORCEPROP 2 LAST CDS_LIB pure_quanta_power
J 0
(-825 4125);
PAINT MONO (-825 4125);
DISPLAY INVISIBLE (-825 4125);
FORCEPROP 1 LAST HDL_POWER GND
J 1
(-800 4050);
DISPLAY 0.872340 (-800 4050);
PAINT GREEN (-800 4050);
DISPLAY INVISIBLE (-800 4050);
FORCEPROP 1 LAST PATH I108
J 0
(-750 4125);
DISPLAY 0.872340 (-750 4125);
PAINT AQUA (-750 4125);
DISPLAY INVISIBLE (-750 4125);
FORCEADD Q_CAP..1
(-825 4500);
FORCEPROP 1 LAST LOCATION C2402
J 0
(-775 4600);
DISPLAY 0.489362 (-775 4600);
PAINT SKYBLUE (-775 4600);
FORCEPROP 2 LAST $SEC 1
J 0
(-775 4700);
DISPLAY 0.680851 (-775 4700);
PAINT MONO (-775 4700);
DISPLAY INVISIBLE (-775 4700);
FORCEPROP 2 LAST CDS_SEC 1
J 0
(-775 4700);
DISPLAY 1.021277 (-775 4700);
DISPLAY INVISIBLE (-775 4700);
FORCEPROP 1 LASTPIN (-825 4600) $PN 1
J 0
(-815 4580);
DISPLAY 0.489362 (-815 4580);
FORCEPROP 1 LASTPIN (-825 4400) $PN 2
J 0
(-815 4380);
DISPLAY 0.489362 (-815 4380);
FORCEPROP 1 LAST MATERIAL X6S
J 0
(-775 4400);
DISPLAY 0.489362 (-775 4400);
PAINT SKYBLUE (-775 4400);
FORCEPROP 1 LAST TOLERANCE 20%
J 0
(-775 4450);
DISPLAY 0.489362 (-775 4450);
PAINT SKYBLUE (-775 4450);
FORCEPROP 1 LAST VALUE 22UF
J 0
(-775 4550);
DISPLAY 0.489362 (-775 4550);
PAINT SKYBLUE (-775 4550);
FORCEPROP 1 LAST VOLTAGE 4V
J 0
(-775 4500);
DISPLAY 0.489362 (-775 4500);
PAINT SKYBLUE (-775 4500);
FORCEPROP 1 LAST PACK_TYPE C0402
J 0
(-775 4300);
DISPLAY 0.489362 (-775 4300);
PAINT SKYBLUE (-775 4300);
FORCEPROP 2 LAST CDS_LIB pure_quanta
J 0
(-825 4500);
PAINT MONO (-825 4500);
DISPLAY INVISIBLE (-825 4500);
FORCEPROP 1 LAST PATH I109
J 0
(-775 4650);
DISPLAY 0.978723 (-775 4650);
PAINT WHITE (-775 4650);
DISPLAY INVISIBLE (-775 4650);
FORCEPROP 1 LAST PART_NUMBER CH622KMEB02
J 0
(-775 4350);
DISPLAY 0.489362 (-775 4350);
PAINT SKYBLUE (-775 4350);
DISPLAY INVISIBLE (-775 4350);
FORCEADD Q_CAP..1
(-8500 2125);
FORCEPROP 1 LAST LOCATION C2309
J 0
(-8450 2225);
DISPLAY 0.489362 (-8450 2225);
PAINT SKYBLUE (-8450 2225);
FORCEPROP 2 LAST $SEC 1
J 0
(-8450 2325);
DISPLAY 0.680851 (-8450 2325);
PAINT MONO (-8450 2325);
DISPLAY INVISIBLE (-8450 2325);
FORCEPROP 2 LAST CDS_SEC 1
J 0
(-8450 2325);
DISPLAY 1.021277 (-8450 2325);
DISPLAY INVISIBLE (-8450 2325);
FORCEPROP 1 LASTPIN (-8500 2225) $PN 1
J 0
(-8490 2205);
DISPLAY 0.489362 (-8490 2205);
FORCEPROP 1 LASTPIN (-8500 2025) $PN 2
J 0
(-8490 2005);
DISPLAY 0.489362 (-8490 2005);
FORCEPROP 1 LAST MATERIAL X6S
J 0
(-8450 2025);
DISPLAY 0.489362 (-8450 2025);
PAINT SKYBLUE (-8450 2025);
FORCEPROP 1 LAST TOLERANCE 20%
J 0
(-8450 2075);
DISPLAY 0.489362 (-8450 2075);
PAINT SKYBLUE (-8450 2075);
FORCEPROP 1 LAST VALUE 22UF
J 0
(-8450 2175);
DISPLAY 0.489362 (-8450 2175);
PAINT SKYBLUE (-8450 2175);
FORCEPROP 1 LAST VOLTAGE 4V
J 0
(-8450 2125);
DISPLAY 0.489362 (-8450 2125);
PAINT SKYBLUE (-8450 2125);
FORCEPROP 1 LAST PACK_TYPE C0402
J 0
(-8450 1925);
DISPLAY 0.489362 (-8450 1925);
PAINT SKYBLUE (-8450 1925);
FORCEPROP 2 LAST CDS_LIB pure_quanta
J 0
(-8500 2125);
PAINT MONO (-8500 2125);
DISPLAY INVISIBLE (-8500 2125);
FORCEPROP 1 LAST PATH I11
J 0
(-8450 2275);
DISPLAY 0.978723 (-8450 2275);
PAINT WHITE (-8450 2275);
DISPLAY INVISIBLE (-8450 2275);
FORCEPROP 1 LAST PART_NUMBER CH622KMEB02
J 0
(-8450 1975);
DISPLAY 0.489362 (-8450 1975);
PAINT SKYBLUE (-8450 1975);
DISPLAY INVISIBLE (-8450 1975);
FORCEADD Q_CAP..1
(-4825 4500);
FORCEPROP 1 LAST LOCATION C2350
J 0
(-4775 4600);
DISPLAY 0.489362 (-4775 4600);
PAINT SKYBLUE (-4775 4600);
FORCEPROP 2 LAST $SEC 1
J 0
(-4775 4700);
DISPLAY 0.680851 (-4775 4700);
PAINT MONO (-4775 4700);
DISPLAY INVISIBLE (-4775 4700);
FORCEPROP 2 LAST CDS_SEC 1
J 0
(-4775 4700);
DISPLAY 1.021277 (-4775 4700);
DISPLAY INVISIBLE (-4775 4700);
FORCEPROP 1 LASTPIN (-4825 4600) $PN 1
J 0
(-4815 4580);
DISPLAY 0.489362 (-4815 4580);
FORCEPROP 1 LASTPIN (-4825 4400) $PN 2
J 0
(-4815 4380);
DISPLAY 0.489362 (-4815 4380);
FORCEPROP 1 LAST MATERIAL X6S
J 0
(-4775 4400);
DISPLAY 0.489362 (-4775 4400);
PAINT SKYBLUE (-4775 4400);
FORCEPROP 1 LAST TOLERANCE 20%
J 0
(-4775 4450);
DISPLAY 0.489362 (-4775 4450);
PAINT SKYBLUE (-4775 4450);
FORCEPROP 1 LAST VALUE 22UF
J 0
(-4775 4550);
DISPLAY 0.489362 (-4775 4550);
PAINT SKYBLUE (-4775 4550);
FORCEPROP 1 LAST VOLTAGE 4V
J 0
(-4775 4500);
DISPLAY 0.489362 (-4775 4500);
PAINT SKYBLUE (-4775 4500);
FORCEPROP 1 LAST PACK_TYPE C0402
J 0
(-4775 4300);
DISPLAY 0.489362 (-4775 4300);
PAINT SKYBLUE (-4775 4300);
FORCEPROP 2 LAST CDS_LIB pure_quanta
J 0
(-4825 4500);
PAINT MONO (-4825 4500);
DISPLAY INVISIBLE (-4825 4500);
FORCEPROP 1 LAST PATH I110
J 0
(-4775 4650);
DISPLAY 0.978723 (-4775 4650);
PAINT WHITE (-4775 4650);
DISPLAY INVISIBLE (-4775 4650);
FORCEPROP 1 LAST PART_NUMBER CH622KMEB02
J 0
(-4775 4350);
DISPLAY 0.489362 (-4775 4350);
PAINT SKYBLUE (-4775 4350);
DISPLAY INVISIBLE (-4775 4350);
FORCEADD Q_CAP..1
(-8950 2925);
FORCEPROP 1 LAST LOCATION C2302
J 0
(-8900 3025);
DISPLAY 0.489362 (-8900 3025);
PAINT SKYBLUE (-8900 3025);
FORCEPROP 2 LAST $SEC 1
J 0
(-8900 3125);
DISPLAY 0.680851 (-8900 3125);
PAINT MONO (-8900 3125);
DISPLAY INVISIBLE (-8900 3125);
FORCEPROP 2 LAST CDS_SEC 1
J 0
(-8900 3125);
DISPLAY 1.021277 (-8900 3125);
DISPLAY INVISIBLE (-8900 3125);
FORCEPROP 1 LASTPIN (-8950 3025) $PN 1
J 0
(-8940 3005);
DISPLAY 0.489362 (-8940 3005);
FORCEPROP 1 LASTPIN (-8950 2825) $PN 2
J 0
(-8940 2805);
DISPLAY 0.489362 (-8940 2805);
FORCEPROP 1 LAST MATERIAL X6S
J 0
(-8900 2825);
DISPLAY 0.489362 (-8900 2825);
PAINT SKYBLUE (-8900 2825);
FORCEPROP 1 LAST TOLERANCE 20%
J 0
(-8900 2875);
DISPLAY 0.489362 (-8900 2875);
PAINT SKYBLUE (-8900 2875);
FORCEPROP 1 LAST VALUE 22UF
J 0
(-8900 2975);
DISPLAY 0.489362 (-8900 2975);
PAINT SKYBLUE (-8900 2975);
FORCEPROP 1 LAST VOLTAGE 4V
J 0
(-8900 2925);
DISPLAY 0.489362 (-8900 2925);
PAINT SKYBLUE (-8900 2925);
FORCEPROP 1 LAST PACK_TYPE C0402
J 0
(-8900 2725);
DISPLAY 0.489362 (-8900 2725);
PAINT SKYBLUE (-8900 2725);
FORCEPROP 2 LAST CDS_LIB pure_quanta
J 0
(-8950 2925);
PAINT MONO (-8950 2925);
DISPLAY INVISIBLE (-8950 2925);
FORCEPROP 1 LAST PATH I12
J 0
(-8900 3075);
DISPLAY 0.978723 (-8900 3075);
PAINT WHITE (-8900 3075);
DISPLAY INVISIBLE (-8900 3075);
FORCEPROP 1 LAST PART_NUMBER CH622KMEB02
J 0
(-8900 2775);
DISPLAY 0.489362 (-8900 2775);
PAINT SKYBLUE (-8900 2775);
DISPLAY INVISIBLE (-8900 2775);
FORCEADD Q_CAP..1
(-8950 3725);
FORCEPROP 1 LAST LOCATION C2301
J 0
(-8900 3825);
DISPLAY 0.489362 (-8900 3825);
PAINT SKYBLUE (-8900 3825);
FORCEPROP 2 LAST $SEC 1
J 0
(-8900 3925);
DISPLAY 0.680851 (-8900 3925);
PAINT MONO (-8900 3925);
DISPLAY INVISIBLE (-8900 3925);
FORCEPROP 2 LAST CDS_SEC 1
J 0
(-8900 3925);
DISPLAY 1.021277 (-8900 3925);
DISPLAY INVISIBLE (-8900 3925);
FORCEPROP 1 LASTPIN (-8950 3825) $PN 1
J 0
(-8940 3805);
DISPLAY 0.489362 (-8940 3805);
FORCEPROP 1 LASTPIN (-8950 3625) $PN 2
J 0
(-8940 3605);
DISPLAY 0.489362 (-8940 3605);
FORCEPROP 1 LAST MATERIAL X6S
J 0
(-8900 3625);
DISPLAY 0.489362 (-8900 3625);
PAINT SKYBLUE (-8900 3625);
FORCEPROP 1 LAST TOLERANCE 20%
J 0
(-8900 3675);
DISPLAY 0.489362 (-8900 3675);
PAINT SKYBLUE (-8900 3675);
FORCEPROP 1 LAST VALUE 22UF
J 0
(-8900 3775);
DISPLAY 0.489362 (-8900 3775);
PAINT SKYBLUE (-8900 3775);
FORCEPROP 1 LAST VOLTAGE 4V
J 0
(-8900 3725);
DISPLAY 0.489362 (-8900 3725);
PAINT SKYBLUE (-8900 3725);
FORCEPROP 1 LAST PACK_TYPE C0402
J 0
(-8900 3525);
DISPLAY 0.489362 (-8900 3525);
PAINT SKYBLUE (-8900 3525);
FORCEPROP 2 LAST CDS_LIB pure_quanta
J 0
(-8950 3725);
PAINT MONO (-8950 3725);
DISPLAY INVISIBLE (-8950 3725);
FORCEPROP 1 LAST PATH I13
J 0
(-8900 3875);
DISPLAY 0.978723 (-8900 3875);
PAINT WHITE (-8900 3875);
DISPLAY INVISIBLE (-8900 3875);
FORCEPROP 1 LAST PART_NUMBER CH622KMEB02
J 0
(-8900 3575);
DISPLAY 0.489362 (-8900 3575);
PAINT SKYBLUE (-8900 3575);
DISPLAY INVISIBLE (-8900 3575);
FORCEADD Q_CAP..1
(-8500 2925);
FORCEPROP 1 LAST LOCATION C2308
J 0
(-8450 3025);
DISPLAY 0.489362 (-8450 3025);
PAINT SKYBLUE (-8450 3025);
FORCEPROP 2 LAST $SEC 1
J 0
(-8450 3125);
DISPLAY 0.680851 (-8450 3125);
PAINT MONO (-8450 3125);
DISPLAY INVISIBLE (-8450 3125);
FORCEPROP 2 LAST CDS_SEC 1
J 0
(-8450 3125);
DISPLAY 1.021277 (-8450 3125);
DISPLAY INVISIBLE (-8450 3125);
FORCEPROP 1 LASTPIN (-8500 3025) $PN 1
J 0
(-8490 3005);
DISPLAY 0.489362 (-8490 3005);
FORCEPROP 1 LASTPIN (-8500 2825) $PN 2
J 0
(-8490 2805);
DISPLAY 0.489362 (-8490 2805);
FORCEPROP 1 LAST MATERIAL X6S
J 0
(-8450 2825);
DISPLAY 0.489362 (-8450 2825);
PAINT SKYBLUE (-8450 2825);
FORCEPROP 1 LAST TOLERANCE 20%
J 0
(-8450 2875);
DISPLAY 0.489362 (-8450 2875);
PAINT SKYBLUE (-8450 2875);
FORCEPROP 1 LAST VALUE 22UF
J 0
(-8450 2975);
DISPLAY 0.489362 (-8450 2975);
PAINT SKYBLUE (-8450 2975);
FORCEPROP 1 LAST VOLTAGE 4V
J 0
(-8450 2925);
DISPLAY 0.489362 (-8450 2925);
PAINT SKYBLUE (-8450 2925);
FORCEPROP 1 LAST PACK_TYPE C0402
J 0
(-8450 2725);
DISPLAY 0.489362 (-8450 2725);
PAINT SKYBLUE (-8450 2725);
FORCEPROP 2 LAST CDS_LIB pure_quanta
J 0
(-8500 2925);
PAINT MONO (-8500 2925);
DISPLAY INVISIBLE (-8500 2925);
FORCEPROP 1 LAST PATH I14
J 0
(-8450 3075);
DISPLAY 0.978723 (-8450 3075);
PAINT WHITE (-8450 3075);
DISPLAY INVISIBLE (-8450 3075);
FORCEPROP 1 LAST PART_NUMBER CH622KMEB02
J 0
(-8450 2775);
DISPLAY 0.489362 (-8450 2775);
PAINT SKYBLUE (-8450 2775);
DISPLAY INVISIBLE (-8450 2775);
FORCEADD Q_CAP..1
(-8500 3725);
FORCEPROP 1 LAST LOCATION C2307
J 0
(-8450 3825);
DISPLAY 0.489362 (-8450 3825);
PAINT SKYBLUE (-8450 3825);
FORCEPROP 2 LAST $SEC 1
J 0
(-8450 3925);
DISPLAY 0.680851 (-8450 3925);
PAINT MONO (-8450 3925);
DISPLAY INVISIBLE (-8450 3925);
FORCEPROP 2 LAST CDS_SEC 1
J 0
(-8450 3925);
DISPLAY 1.021277 (-8450 3925);
DISPLAY INVISIBLE (-8450 3925);
FORCEPROP 1 LASTPIN (-8500 3825) $PN 1
J 0
(-8490 3805);
DISPLAY 0.489362 (-8490 3805);
FORCEPROP 1 LASTPIN (-8500 3625) $PN 2
J 0
(-8490 3605);
DISPLAY 0.489362 (-8490 3605);
FORCEPROP 1 LAST MATERIAL X6S
J 0
(-8450 3625);
DISPLAY 0.489362 (-8450 3625);
PAINT SKYBLUE (-8450 3625);
FORCEPROP 1 LAST TOLERANCE 20%
J 0
(-8450 3675);
DISPLAY 0.489362 (-8450 3675);
PAINT SKYBLUE (-8450 3675);
FORCEPROP 1 LAST VALUE 22UF
J 0
(-8450 3775);
DISPLAY 0.489362 (-8450 3775);
PAINT SKYBLUE (-8450 3775);
FORCEPROP 1 LAST VOLTAGE 4V
J 0
(-8450 3725);
DISPLAY 0.489362 (-8450 3725);
PAINT SKYBLUE (-8450 3725);
FORCEPROP 1 LAST PACK_TYPE C0402
J 0
(-8450 3525);
DISPLAY 0.489362 (-8450 3525);
PAINT SKYBLUE (-8450 3525);
FORCEPROP 2 LAST CDS_LIB pure_quanta
J 0
(-8500 3725);
PAINT MONO (-8500 3725);
DISPLAY INVISIBLE (-8500 3725);
FORCEPROP 1 LAST PATH I15
J 0
(-8450 3875);
DISPLAY 0.978723 (-8450 3875);
PAINT WHITE (-8450 3875);
DISPLAY INVISIBLE (-8450 3875);
FORCEPROP 1 LAST PART_NUMBER CH622KMEB02
J 0
(-8450 3575);
DISPLAY 0.489362 (-8450 3575);
PAINT SKYBLUE (-8450 3575);
DISPLAY INVISIBLE (-8450 3575);
FORCEADD UNIVERSAL_POWER..1
(-9400 4000);
FORCEPROP 3 LASTPIN (-9400 3950) SIG_NAME PVDDCR_CPU0_P1\g
J 0
(-9390 3960);
DISPLAY 0.659574 (-9390 3960);
PAINT MONO (-9390 3960);
DISPLAY INVISIBLE (-9390 3960);
FORCEPROP 1 LAST HDL_POWER PVDDCR_CPU0_P1
J 1
(-9400 4050);
DISPLAY 0.489362 (-9400 4050);
PAINT GREEN (-9400 4050);
FORCEPROP 2 LAST CDS_LIB pure_quanta_power
J 0
(-9400 4000);
DISPLAY INVISIBLE (-9400 4000);
FORCEPROP 1 LAST PATH I16
J 0
(-9350 4025);
DISPLAY 0.872340 (-9350 4025);
PAINT AQUA (-9350 4025);
DISPLAY INVISIBLE (-9350 4025);
FORCEADD Q_CAP..1
(-9400 4500);
FORCEPROP 1 LAST LOCATION C2294
J 0
(-9350 4600);
DISPLAY 0.489362 (-9350 4600);
PAINT SKYBLUE (-9350 4600);
FORCEPROP 2 LAST $SEC 1
J 0
(-9350 4700);
DISPLAY 0.680851 (-9350 4700);
PAINT MONO (-9350 4700);
DISPLAY INVISIBLE (-9350 4700);
FORCEPROP 2 LAST CDS_SEC 1
J 0
(-9350 4700);
DISPLAY 1.021277 (-9350 4700);
DISPLAY INVISIBLE (-9350 4700);
FORCEPROP 1 LASTPIN (-9400 4600) $PN 1
J 0
(-9390 4580);
DISPLAY 0.489362 (-9390 4580);
FORCEPROP 1 LASTPIN (-9400 4400) $PN 2
J 0
(-9390 4380);
DISPLAY 0.489362 (-9390 4380);
FORCEPROP 1 LAST MATERIAL X6S
J 0
(-9350 4400);
DISPLAY 0.489362 (-9350 4400);
PAINT SKYBLUE (-9350 4400);
FORCEPROP 1 LAST TOLERANCE 20%
J 0
(-9350 4450);
DISPLAY 0.489362 (-9350 4450);
PAINT SKYBLUE (-9350 4450);
FORCEPROP 1 LAST VALUE 22UF
J 0
(-9350 4550);
DISPLAY 0.489362 (-9350 4550);
PAINT SKYBLUE (-9350 4550);
FORCEPROP 1 LAST VOLTAGE 4V
J 0
(-9350 4500);
DISPLAY 0.489362 (-9350 4500);
PAINT SKYBLUE (-9350 4500);
FORCEPROP 1 LAST PACK_TYPE C0402
J 0
(-9350 4300);
DISPLAY 0.489362 (-9350 4300);
PAINT SKYBLUE (-9350 4300);
FORCEPROP 2 LAST CDS_LIB pure_quanta
J 0
(-9400 4500);
PAINT MONO (-9400 4500);
DISPLAY INVISIBLE (-9400 4500);
FORCEPROP 1 LAST PATH I17
J 0
(-9350 4650);
DISPLAY 0.978723 (-9350 4650);
PAINT WHITE (-9350 4650);
DISPLAY INVISIBLE (-9350 4650);
FORCEPROP 1 LAST PART_NUMBER CH622KMEB02
J 0
(-9350 4350);
DISPLAY 0.489362 (-9350 4350);
PAINT SKYBLUE (-9350 4350);
DISPLAY INVISIBLE (-9350 4350);
FORCEADD UNIVERSAL_POWER..1
(-9400 4775);
FORCEPROP 3 LASTPIN (-9400 4725) SIG_NAME PVDDCR_CPU0_P1\g
J 0
(-9390 4735);
DISPLAY 0.659574 (-9390 4735);
PAINT MONO (-9390 4735);
DISPLAY INVISIBLE (-9390 4735);
FORCEPROP 1 LAST HDL_POWER PVDDCR_CPU0_P1
J 1
(-9400 4825);
DISPLAY 0.489362 (-9400 4825);
PAINT GREEN (-9400 4825);
FORCEPROP 2 LAST CDS_LIB pure_quanta_power
J 0
(-9400 4775);
DISPLAY INVISIBLE (-9400 4775);
FORCEPROP 1 LAST PATH I18
J 0
(-9350 4800);
DISPLAY 0.872340 (-9350 4800);
PAINT AQUA (-9350 4800);
DISPLAY INVISIBLE (-9350 4800);
FORCEADD Q_CAP..1
(-8950 4500);
FORCEPROP 1 LAST LOCATION C2300
J 0
(-8900 4600);
DISPLAY 0.489362 (-8900 4600);
PAINT SKYBLUE (-8900 4600);
FORCEPROP 2 LAST $SEC 1
J 0
(-8900 4700);
DISPLAY 0.680851 (-8900 4700);
PAINT MONO (-8900 4700);
DISPLAY INVISIBLE (-8900 4700);
FORCEPROP 2 LAST CDS_SEC 1
J 0
(-8900 4700);
DISPLAY 1.021277 (-8900 4700);
DISPLAY INVISIBLE (-8900 4700);
FORCEPROP 1 LASTPIN (-8950 4600) $PN 1
J 0
(-8940 4580);
DISPLAY 0.489362 (-8940 4580);
FORCEPROP 1 LASTPIN (-8950 4400) $PN 2
J 0
(-8940 4380);
DISPLAY 0.489362 (-8940 4380);
FORCEPROP 1 LAST MATERIAL X6S
J 0
(-8900 4400);
DISPLAY 0.489362 (-8900 4400);
PAINT SKYBLUE (-8900 4400);
FORCEPROP 1 LAST TOLERANCE 20%
J 0
(-8900 4450);
DISPLAY 0.489362 (-8900 4450);
PAINT SKYBLUE (-8900 4450);
FORCEPROP 1 LAST VALUE 22UF
J 0
(-8900 4550);
DISPLAY 0.489362 (-8900 4550);
PAINT SKYBLUE (-8900 4550);
FORCEPROP 1 LAST VOLTAGE 4V
J 0
(-8900 4500);
DISPLAY 0.489362 (-8900 4500);
PAINT SKYBLUE (-8900 4500);
FORCEPROP 1 LAST PACK_TYPE C0402
J 0
(-8900 4300);
DISPLAY 0.489362 (-8900 4300);
PAINT SKYBLUE (-8900 4300);
FORCEPROP 2 LAST CDS_LIB pure_quanta
J 0
(-8950 4500);
PAINT MONO (-8950 4500);
DISPLAY INVISIBLE (-8950 4500);
FORCEPROP 1 LAST PATH I19
J 0
(-8900 4650);
DISPLAY 0.978723 (-8900 4650);
PAINT WHITE (-8900 4650);
DISPLAY INVISIBLE (-8900 4650);
FORCEPROP 1 LAST PART_NUMBER CH622KMEB02
J 0
(-8900 4350);
DISPLAY 0.489362 (-8900 4350);
PAINT SKYBLUE (-8900 4350);
DISPLAY INVISIBLE (-8900 4350);
FORCEADD UNIVERSAL_POWER..1
(-9400 1600);
FORCEPROP 3 LASTPIN (-9400 1550) SIG_NAME PVDDCR_CPU0_P1\g
J 0
(-9390 1560);
DISPLAY 0.659574 (-9390 1560);
PAINT MONO (-9390 1560);
DISPLAY INVISIBLE (-9390 1560);
FORCEPROP 1 LAST HDL_POWER PVDDCR_CPU0_P1
J 1
(-9400 1650);
DISPLAY 0.489362 (-9400 1650);
PAINT GREEN (-9400 1650);
FORCEPROP 2 LAST CDS_LIB pure_quanta_power
J 0
(-9400 1600);
DISPLAY INVISIBLE (-9400 1600);
FORCEPROP 1 LAST PATH I2
J 0
(-9350 1625);
DISPLAY 0.872340 (-9350 1625);
PAINT AQUA (-9350 1625);
DISPLAY INVISIBLE (-9350 1625);
FORCEADD Q_CAP..1
(-8500 4500);
FORCEPROP 1 LAST LOCATION C2306
J 0
(-8450 4600);
DISPLAY 0.489362 (-8450 4600);
PAINT SKYBLUE (-8450 4600);
FORCEPROP 2 LAST $SEC 1
J 0
(-8450 4700);
DISPLAY 0.680851 (-8450 4700);
PAINT MONO (-8450 4700);
DISPLAY INVISIBLE (-8450 4700);
FORCEPROP 2 LAST CDS_SEC 1
J 0
(-8450 4700);
DISPLAY 1.021277 (-8450 4700);
DISPLAY INVISIBLE (-8450 4700);
FORCEPROP 1 LASTPIN (-8500 4600) $PN 1
J 0
(-8490 4580);
DISPLAY 0.489362 (-8490 4580);
FORCEPROP 1 LASTPIN (-8500 4400) $PN 2
J 0
(-8490 4380);
DISPLAY 0.489362 (-8490 4380);
FORCEPROP 1 LAST MATERIAL X6S
J 0
(-8450 4400);
DISPLAY 0.489362 (-8450 4400);
PAINT SKYBLUE (-8450 4400);
FORCEPROP 1 LAST TOLERANCE 20%
J 0
(-8450 4450);
DISPLAY 0.489362 (-8450 4450);
PAINT SKYBLUE (-8450 4450);
FORCEPROP 1 LAST VALUE 22UF
J 0
(-8450 4550);
DISPLAY 0.489362 (-8450 4550);
PAINT SKYBLUE (-8450 4550);
FORCEPROP 1 LAST VOLTAGE 4V
J 0
(-8450 4500);
DISPLAY 0.489362 (-8450 4500);
PAINT SKYBLUE (-8450 4500);
FORCEPROP 1 LAST PACK_TYPE C0402
J 0
(-8450 4300);
DISPLAY 0.489362 (-8450 4300);
PAINT SKYBLUE (-8450 4300);
FORCEPROP 2 LAST CDS_LIB pure_quanta
J 0
(-8500 4500);
PAINT MONO (-8500 4500);
DISPLAY INVISIBLE (-8500 4500);
FORCEPROP 1 LAST PATH I20
J 0
(-8450 4650);
DISPLAY 0.978723 (-8450 4650);
PAINT WHITE (-8450 4650);
DISPLAY INVISIBLE (-8450 4650);
FORCEPROP 1 LAST PART_NUMBER CH622KMEB02
J 0
(-8450 4350);
DISPLAY 0.489362 (-8450 4350);
PAINT SKYBLUE (-8450 4350);
DISPLAY INVISIBLE (-8450 4350);
FORCEADD Q_CAP..1
(-8050 1325);
FORCEPROP 1 LAST LOCATION C2316
J 0
(-8000 1425);
DISPLAY 0.489362 (-8000 1425);
PAINT SKYBLUE (-8000 1425);
FORCEPROP 2 LAST $SEC 1
J 0
(-8000 1525);
DISPLAY 0.680851 (-8000 1525);
PAINT MONO (-8000 1525);
DISPLAY INVISIBLE (-8000 1525);
FORCEPROP 2 LAST CDS_SEC 1
J 0
(-8000 1525);
DISPLAY 1.021277 (-8000 1525);
DISPLAY INVISIBLE (-8000 1525);
FORCEPROP 1 LASTPIN (-8050 1425) $PN 1
J 0
(-8040 1405);
DISPLAY 0.489362 (-8040 1405);
FORCEPROP 1 LASTPIN (-8050 1225) $PN 2
J 0
(-8040 1205);
DISPLAY 0.489362 (-8040 1205);
FORCEPROP 1 LAST MATERIAL X6S
J 0
(-8000 1225);
DISPLAY 0.489362 (-8000 1225);
PAINT SKYBLUE (-8000 1225);
FORCEPROP 1 LAST TOLERANCE 20%
J 0
(-8000 1275);
DISPLAY 0.489362 (-8000 1275);
PAINT SKYBLUE (-8000 1275);
FORCEPROP 1 LAST VALUE 22UF
J 0
(-8000 1375);
DISPLAY 0.489362 (-8000 1375);
PAINT SKYBLUE (-8000 1375);
FORCEPROP 1 LAST VOLTAGE 4V
J 0
(-8000 1325);
DISPLAY 0.489362 (-8000 1325);
PAINT SKYBLUE (-8000 1325);
FORCEPROP 1 LAST PACK_TYPE C0402
J 0
(-8000 1125);
DISPLAY 0.489362 (-8000 1125);
PAINT SKYBLUE (-8000 1125);
FORCEPROP 2 LAST CDS_LIB pure_quanta
J 0
(-8050 1325);
PAINT MONO (-8050 1325);
DISPLAY INVISIBLE (-8050 1325);
FORCEPROP 1 LAST PATH I21
J 0
(-8000 1475);
DISPLAY 0.978723 (-8000 1475);
PAINT WHITE (-8000 1475);
DISPLAY INVISIBLE (-8000 1475);
FORCEPROP 1 LAST PART_NUMBER CH622KMEB02
J 0
(-8000 1175);
DISPLAY 0.489362 (-8000 1175);
PAINT SKYBLUE (-8000 1175);
DISPLAY INVISIBLE (-8000 1175);
FORCEADD UNIVERSAL_GND..1
(-7600 950);
FORCEPROP 3 LASTPIN (-7600 1000) SIG_NAME GND\g
J 0
(-7590 1010);
DISPLAY 0.659574 (-7590 1010);
PAINT MONO (-7590 1010);
DISPLAY INVISIBLE (-7590 1010);
FORCEPROP 2 LAST CDS_LIB pure_quanta_power
J 0
(-7600 950);
DISPLAY INVISIBLE (-7600 950);
FORCEPROP 1 LAST HDL_POWER GND
J 1
(-7575 875);
DISPLAY 0.872340 (-7575 875);
PAINT GREEN (-7575 875);
DISPLAY INVISIBLE (-7575 875);
FORCEPROP 1 LAST PATH I22
J 0
(-7525 950);
DISPLAY 0.872340 (-7525 950);
PAINT AQUA (-7525 950);
DISPLAY INVISIBLE (-7525 950);
FORCEADD Q_CAP..1
(-7600 1325);
FORCEPROP 1 LAST LOCATION C2322
J 0
(-7550 1425);
DISPLAY 0.489362 (-7550 1425);
PAINT SKYBLUE (-7550 1425);
FORCEPROP 2 LAST $SEC 1
J 0
(-7550 1525);
DISPLAY 0.680851 (-7550 1525);
PAINT MONO (-7550 1525);
DISPLAY INVISIBLE (-7550 1525);
FORCEPROP 2 LAST CDS_SEC 1
J 0
(-7550 1525);
DISPLAY 1.021277 (-7550 1525);
DISPLAY INVISIBLE (-7550 1525);
FORCEPROP 1 LASTPIN (-7600 1425) $PN 1
J 0
(-7590 1405);
DISPLAY 0.489362 (-7590 1405);
FORCEPROP 1 LASTPIN (-7600 1225) $PN 2
J 0
(-7590 1205);
DISPLAY 0.489362 (-7590 1205);
FORCEPROP 1 LAST MATERIAL X6S
J 0
(-7550 1225);
DISPLAY 0.489362 (-7550 1225);
PAINT SKYBLUE (-7550 1225);
FORCEPROP 1 LAST TOLERANCE 20%
J 0
(-7550 1275);
DISPLAY 0.489362 (-7550 1275);
PAINT SKYBLUE (-7550 1275);
FORCEPROP 1 LAST VALUE 22UF
J 0
(-7550 1375);
DISPLAY 0.489362 (-7550 1375);
PAINT SKYBLUE (-7550 1375);
FORCEPROP 1 LAST VOLTAGE 4V
J 0
(-7550 1325);
DISPLAY 0.489362 (-7550 1325);
PAINT SKYBLUE (-7550 1325);
FORCEPROP 1 LAST PACK_TYPE C0402
J 0
(-7550 1125);
DISPLAY 0.489362 (-7550 1125);
PAINT SKYBLUE (-7550 1125);
FORCEPROP 2 LAST CDS_LIB pure_quanta
J 0
(-7600 1325);
PAINT MONO (-7600 1325);
DISPLAY INVISIBLE (-7600 1325);
FORCEPROP 1 LAST PATH I23
J 0
(-7550 1475);
DISPLAY 0.978723 (-7550 1475);
PAINT WHITE (-7550 1475);
DISPLAY INVISIBLE (-7550 1475);
FORCEPROP 1 LAST PART_NUMBER CH622KMEB02
J 0
(-7550 1175);
DISPLAY 0.489362 (-7550 1175);
PAINT SKYBLUE (-7550 1175);
DISPLAY INVISIBLE (-7550 1175);
FORCEADD Q_CAP..1
(-8050 2125);
FORCEPROP 1 LAST LOCATION C2315
J 0
(-8000 2225);
DISPLAY 0.489362 (-8000 2225);
PAINT SKYBLUE (-8000 2225);
FORCEPROP 2 LAST $SEC 1
J 0
(-8000 2325);
DISPLAY 0.680851 (-8000 2325);
PAINT MONO (-8000 2325);
DISPLAY INVISIBLE (-8000 2325);
FORCEPROP 2 LAST CDS_SEC 1
J 0
(-8000 2325);
DISPLAY 1.021277 (-8000 2325);
DISPLAY INVISIBLE (-8000 2325);
FORCEPROP 1 LASTPIN (-8050 2225) $PN 1
J 0
(-8040 2205);
DISPLAY 0.489362 (-8040 2205);
FORCEPROP 1 LASTPIN (-8050 2025) $PN 2
J 0
(-8040 2005);
DISPLAY 0.489362 (-8040 2005);
FORCEPROP 1 LAST MATERIAL X6S
J 0
(-8000 2025);
DISPLAY 0.489362 (-8000 2025);
PAINT SKYBLUE (-8000 2025);
FORCEPROP 1 LAST TOLERANCE 20%
J 0
(-8000 2075);
DISPLAY 0.489362 (-8000 2075);
PAINT SKYBLUE (-8000 2075);
FORCEPROP 1 LAST VALUE 22UF
J 0
(-8000 2175);
DISPLAY 0.489362 (-8000 2175);
PAINT SKYBLUE (-8000 2175);
FORCEPROP 1 LAST VOLTAGE 4V
J 0
(-8000 2125);
DISPLAY 0.489362 (-8000 2125);
PAINT SKYBLUE (-8000 2125);
FORCEPROP 1 LAST PACK_TYPE C0402
J 0
(-8000 1925);
DISPLAY 0.489362 (-8000 1925);
PAINT SKYBLUE (-8000 1925);
FORCEPROP 2 LAST CDS_LIB pure_quanta
J 0
(-8050 2125);
PAINT MONO (-8050 2125);
DISPLAY INVISIBLE (-8050 2125);
FORCEPROP 1 LAST PATH I24
J 0
(-8000 2275);
DISPLAY 0.978723 (-8000 2275);
PAINT WHITE (-8000 2275);
DISPLAY INVISIBLE (-8000 2275);
FORCEPROP 1 LAST PART_NUMBER CH622KMEB02
J 0
(-8000 1975);
DISPLAY 0.489362 (-8000 1975);
PAINT SKYBLUE (-8000 1975);
DISPLAY INVISIBLE (-8000 1975);
FORCEADD Q_CAP..1
(-7600 2125);
FORCEPROP 1 LAST LOCATION C2321
J 0
(-7550 2225);
DISPLAY 0.489362 (-7550 2225);
PAINT SKYBLUE (-7550 2225);
FORCEPROP 2 LAST $SEC 1
J 0
(-7550 2325);
DISPLAY 0.680851 (-7550 2325);
PAINT MONO (-7550 2325);
DISPLAY INVISIBLE (-7550 2325);
FORCEPROP 2 LAST CDS_SEC 1
J 0
(-7550 2325);
DISPLAY 1.021277 (-7550 2325);
DISPLAY INVISIBLE (-7550 2325);
FORCEPROP 1 LASTPIN (-7600 2225) $PN 1
J 0
(-7590 2205);
DISPLAY 0.489362 (-7590 2205);
FORCEPROP 1 LASTPIN (-7600 2025) $PN 2
J 0
(-7590 2005);
DISPLAY 0.489362 (-7590 2005);
FORCEPROP 1 LAST MATERIAL X6S
J 0
(-7550 2025);
DISPLAY 0.489362 (-7550 2025);
PAINT SKYBLUE (-7550 2025);
FORCEPROP 1 LAST TOLERANCE 20%
J 0
(-7550 2075);
DISPLAY 0.489362 (-7550 2075);
PAINT SKYBLUE (-7550 2075);
FORCEPROP 1 LAST VALUE 22UF
J 0
(-7550 2175);
DISPLAY 0.489362 (-7550 2175);
PAINT SKYBLUE (-7550 2175);
FORCEPROP 1 LAST VOLTAGE 4V
J 0
(-7550 2125);
DISPLAY 0.489362 (-7550 2125);
PAINT SKYBLUE (-7550 2125);
FORCEPROP 1 LAST PACK_TYPE C0402
J 0
(-7550 1925);
DISPLAY 0.489362 (-7550 1925);
PAINT SKYBLUE (-7550 1925);
FORCEPROP 2 LAST CDS_LIB pure_quanta
J 0
(-7600 2125);
PAINT MONO (-7600 2125);
DISPLAY INVISIBLE (-7600 2125);
FORCEPROP 1 LAST PATH I25
J 0
(-7550 2275);
DISPLAY 0.978723 (-7550 2275);
PAINT WHITE (-7550 2275);
DISPLAY INVISIBLE (-7550 2275);
FORCEPROP 1 LAST PART_NUMBER CH622KMEB02
J 0
(-7550 1975);
DISPLAY 0.489362 (-7550 1975);
PAINT SKYBLUE (-7550 1975);
DISPLAY INVISIBLE (-7550 1975);
FORCEADD Q_CAP..1
(-7150 2125);
FORCEPROP 1 LAST LOCATION C2327
J 0
(-7100 2225);
DISPLAY 0.489362 (-7100 2225);
PAINT SKYBLUE (-7100 2225);
FORCEPROP 2 LAST $SEC 1
J 0
(-7100 2325);
DISPLAY 0.680851 (-7100 2325);
PAINT MONO (-7100 2325);
DISPLAY INVISIBLE (-7100 2325);
FORCEPROP 2 LAST CDS_SEC 1
J 0
(-7100 2325);
DISPLAY 1.021277 (-7100 2325);
DISPLAY INVISIBLE (-7100 2325);
FORCEPROP 1 LASTPIN (-7150 2225) $PN 1
J 0
(-7140 2205);
DISPLAY 0.489362 (-7140 2205);
FORCEPROP 1 LASTPIN (-7150 2025) $PN 2
J 0
(-7140 2005);
DISPLAY 0.489362 (-7140 2005);
FORCEPROP 1 LAST MATERIAL X6S
J 0
(-7100 2025);
DISPLAY 0.489362 (-7100 2025);
PAINT SKYBLUE (-7100 2025);
FORCEPROP 1 LAST TOLERANCE 20%
J 0
(-7100 2075);
DISPLAY 0.489362 (-7100 2075);
PAINT SKYBLUE (-7100 2075);
FORCEPROP 1 LAST VALUE 22UF
J 0
(-7100 2175);
DISPLAY 0.489362 (-7100 2175);
PAINT SKYBLUE (-7100 2175);
FORCEPROP 1 LAST VOLTAGE 4V
J 0
(-7100 2125);
DISPLAY 0.489362 (-7100 2125);
PAINT SKYBLUE (-7100 2125);
FORCEPROP 1 LAST PACK_TYPE C0402
J 0
(-7100 1925);
DISPLAY 0.489362 (-7100 1925);
PAINT SKYBLUE (-7100 1925);
FORCEPROP 2 LAST CDS_LIB pure_quanta
J 0
(-7150 2125);
PAINT MONO (-7150 2125);
DISPLAY INVISIBLE (-7150 2125);
FORCEPROP 1 LAST PATH I26
J 0
(-7100 2275);
DISPLAY 0.978723 (-7100 2275);
PAINT WHITE (-7100 2275);
DISPLAY INVISIBLE (-7100 2275);
FORCEPROP 1 LAST PART_NUMBER CH622KMEB02
J 0
(-7100 1975);
DISPLAY 0.489362 (-7100 1975);
PAINT SKYBLUE (-7100 1975);
DISPLAY INVISIBLE (-7100 1975);
FORCEADD Q_CAP..1
(-8050 2925);
FORCEPROP 1 LAST LOCATION C2314
J 0
(-8000 3025);
DISPLAY 0.489362 (-8000 3025);
PAINT SKYBLUE (-8000 3025);
FORCEPROP 2 LAST $SEC 1
J 0
(-8000 3125);
DISPLAY 0.680851 (-8000 3125);
PAINT MONO (-8000 3125);
DISPLAY INVISIBLE (-8000 3125);
FORCEPROP 2 LAST CDS_SEC 1
J 0
(-8000 3125);
DISPLAY 1.021277 (-8000 3125);
DISPLAY INVISIBLE (-8000 3125);
FORCEPROP 1 LASTPIN (-8050 3025) $PN 1
J 0
(-8040 3005);
DISPLAY 0.489362 (-8040 3005);
FORCEPROP 1 LASTPIN (-8050 2825) $PN 2
J 0
(-8040 2805);
DISPLAY 0.489362 (-8040 2805);
FORCEPROP 1 LAST MATERIAL X6S
J 0
(-8000 2825);
DISPLAY 0.489362 (-8000 2825);
PAINT SKYBLUE (-8000 2825);
FORCEPROP 1 LAST TOLERANCE 20%
J 0
(-8000 2875);
DISPLAY 0.489362 (-8000 2875);
PAINT SKYBLUE (-8000 2875);
FORCEPROP 1 LAST VALUE 22UF
J 0
(-8000 2975);
DISPLAY 0.489362 (-8000 2975);
PAINT SKYBLUE (-8000 2975);
FORCEPROP 1 LAST VOLTAGE 4V
J 0
(-8000 2925);
DISPLAY 0.489362 (-8000 2925);
PAINT SKYBLUE (-8000 2925);
FORCEPROP 1 LAST PACK_TYPE C0402
J 0
(-8000 2725);
DISPLAY 0.489362 (-8000 2725);
PAINT SKYBLUE (-8000 2725);
FORCEPROP 2 LAST CDS_LIB pure_quanta
J 0
(-8050 2925);
PAINT MONO (-8050 2925);
DISPLAY INVISIBLE (-8050 2925);
FORCEPROP 1 LAST PATH I27
J 0
(-8000 3075);
DISPLAY 0.978723 (-8000 3075);
PAINT WHITE (-8000 3075);
DISPLAY INVISIBLE (-8000 3075);
FORCEPROP 1 LAST PART_NUMBER CH622KMEB02
J 0
(-8000 2775);
DISPLAY 0.489362 (-8000 2775);
PAINT SKYBLUE (-8000 2775);
DISPLAY INVISIBLE (-8000 2775);
FORCEADD Q_CAP..1
(-8050 3725);
FORCEPROP 1 LAST LOCATION C2313
J 0
(-8000 3825);
DISPLAY 0.489362 (-8000 3825);
PAINT SKYBLUE (-8000 3825);
FORCEPROP 2 LAST $SEC 1
J 0
(-8000 3925);
DISPLAY 0.680851 (-8000 3925);
PAINT MONO (-8000 3925);
DISPLAY INVISIBLE (-8000 3925);
FORCEPROP 2 LAST CDS_SEC 1
J 0
(-8000 3925);
DISPLAY 1.021277 (-8000 3925);
DISPLAY INVISIBLE (-8000 3925);
FORCEPROP 1 LASTPIN (-8050 3825) $PN 1
J 0
(-8040 3805);
DISPLAY 0.489362 (-8040 3805);
FORCEPROP 1 LASTPIN (-8050 3625) $PN 2
J 0
(-8040 3605);
DISPLAY 0.489362 (-8040 3605);
FORCEPROP 1 LAST MATERIAL X6S
J 0
(-8000 3625);
DISPLAY 0.489362 (-8000 3625);
PAINT SKYBLUE (-8000 3625);
FORCEPROP 1 LAST TOLERANCE 20%
J 0
(-8000 3675);
DISPLAY 0.489362 (-8000 3675);
PAINT SKYBLUE (-8000 3675);
FORCEPROP 1 LAST VALUE 22UF
J 0
(-8000 3775);
DISPLAY 0.489362 (-8000 3775);
PAINT SKYBLUE (-8000 3775);
FORCEPROP 1 LAST VOLTAGE 4V
J 0
(-8000 3725);
DISPLAY 0.489362 (-8000 3725);
PAINT SKYBLUE (-8000 3725);
FORCEPROP 1 LAST PACK_TYPE C0402
J 0
(-8000 3525);
DISPLAY 0.489362 (-8000 3525);
PAINT SKYBLUE (-8000 3525);
FORCEPROP 2 LAST CDS_LIB pure_quanta
J 0
(-8050 3725);
PAINT MONO (-8050 3725);
DISPLAY INVISIBLE (-8050 3725);
FORCEPROP 1 LAST PATH I28
J 0
(-8000 3875);
DISPLAY 0.978723 (-8000 3875);
PAINT WHITE (-8000 3875);
DISPLAY INVISIBLE (-8000 3875);
FORCEPROP 1 LAST PART_NUMBER CH622KMEB02
J 0
(-8000 3575);
DISPLAY 0.489362 (-8000 3575);
PAINT SKYBLUE (-8000 3575);
DISPLAY INVISIBLE (-8000 3575);
FORCEADD Q_CAP..1
(-7600 2925);
FORCEPROP 1 LAST LOCATION C2320
J 0
(-7550 3025);
DISPLAY 0.489362 (-7550 3025);
PAINT SKYBLUE (-7550 3025);
FORCEPROP 2 LAST $SEC 1
J 0
(-7550 3125);
DISPLAY 0.680851 (-7550 3125);
PAINT MONO (-7550 3125);
DISPLAY INVISIBLE (-7550 3125);
FORCEPROP 2 LAST CDS_SEC 1
J 0
(-7550 3125);
DISPLAY 1.021277 (-7550 3125);
DISPLAY INVISIBLE (-7550 3125);
FORCEPROP 1 LASTPIN (-7600 3025) $PN 1
J 0
(-7590 3005);
DISPLAY 0.489362 (-7590 3005);
FORCEPROP 1 LASTPIN (-7600 2825) $PN 2
J 0
(-7590 2805);
DISPLAY 0.489362 (-7590 2805);
FORCEPROP 1 LAST MATERIAL X6S
J 0
(-7550 2825);
DISPLAY 0.489362 (-7550 2825);
PAINT SKYBLUE (-7550 2825);
FORCEPROP 1 LAST TOLERANCE 20%
J 0
(-7550 2875);
DISPLAY 0.489362 (-7550 2875);
PAINT SKYBLUE (-7550 2875);
FORCEPROP 1 LAST VALUE 22UF
J 0
(-7550 2975);
DISPLAY 0.489362 (-7550 2975);
PAINT SKYBLUE (-7550 2975);
FORCEPROP 1 LAST VOLTAGE 4V
J 0
(-7550 2925);
DISPLAY 0.489362 (-7550 2925);
PAINT SKYBLUE (-7550 2925);
FORCEPROP 1 LAST PACK_TYPE C0402
J 0
(-7550 2725);
DISPLAY 0.489362 (-7550 2725);
PAINT SKYBLUE (-7550 2725);
FORCEPROP 2 LAST CDS_LIB pure_quanta
J 0
(-7600 2925);
PAINT MONO (-7600 2925);
DISPLAY INVISIBLE (-7600 2925);
FORCEPROP 1 LAST PATH I29
J 0
(-7550 3075);
DISPLAY 0.978723 (-7550 3075);
PAINT WHITE (-7550 3075);
DISPLAY INVISIBLE (-7550 3075);
FORCEPROP 1 LAST PART_NUMBER CH622KMEB02
J 0
(-7550 2775);
DISPLAY 0.489362 (-7550 2775);
PAINT SKYBLUE (-7550 2775);
DISPLAY INVISIBLE (-7550 2775);
FORCEADD Q_CAP..1
(-8950 1325);
FORCEPROP 1 LAST LOCATION C2304
J 0
(-8900 1425);
DISPLAY 0.489362 (-8900 1425);
PAINT SKYBLUE (-8900 1425);
FORCEPROP 2 LAST $SEC 1
J 0
(-8900 1525);
DISPLAY 0.680851 (-8900 1525);
PAINT MONO (-8900 1525);
DISPLAY INVISIBLE (-8900 1525);
FORCEPROP 2 LAST CDS_SEC 1
J 0
(-8900 1525);
DISPLAY 1.021277 (-8900 1525);
DISPLAY INVISIBLE (-8900 1525);
FORCEPROP 1 LASTPIN (-8950 1425) $PN 1
J 0
(-8940 1405);
DISPLAY 0.489362 (-8940 1405);
FORCEPROP 1 LASTPIN (-8950 1225) $PN 2
J 0
(-8940 1205);
DISPLAY 0.489362 (-8940 1205);
FORCEPROP 1 LAST MATERIAL X6S
J 0
(-8900 1225);
DISPLAY 0.489362 (-8900 1225);
PAINT SKYBLUE (-8900 1225);
FORCEPROP 1 LAST TOLERANCE 20%
J 0
(-8900 1275);
DISPLAY 0.489362 (-8900 1275);
PAINT SKYBLUE (-8900 1275);
FORCEPROP 1 LAST VALUE 22UF
J 0
(-8900 1375);
DISPLAY 0.489362 (-8900 1375);
PAINT SKYBLUE (-8900 1375);
FORCEPROP 1 LAST VOLTAGE 4V
J 0
(-8900 1325);
DISPLAY 0.489362 (-8900 1325);
PAINT SKYBLUE (-8900 1325);
FORCEPROP 1 LAST PACK_TYPE C0402
J 0
(-8900 1125);
DISPLAY 0.489362 (-8900 1125);
PAINT SKYBLUE (-8900 1125);
FORCEPROP 2 LAST CDS_LIB pure_quanta
J 0
(-8950 1325);
PAINT MONO (-8950 1325);
DISPLAY INVISIBLE (-8950 1325);
FORCEPROP 1 LAST PATH I3
J 0
(-8900 1475);
DISPLAY 0.978723 (-8900 1475);
PAINT WHITE (-8900 1475);
DISPLAY INVISIBLE (-8900 1475);
FORCEPROP 1 LAST PART_NUMBER CH622KMEB02
J 0
(-8900 1175);
DISPLAY 0.489362 (-8900 1175);
PAINT SKYBLUE (-8900 1175);
DISPLAY INVISIBLE (-8900 1175);
FORCEADD Q_CAP..1
(-7150 2925);
FORCEPROP 1 LAST LOCATION C2326
J 0
(-7100 3025);
DISPLAY 0.489362 (-7100 3025);
PAINT SKYBLUE (-7100 3025);
FORCEPROP 2 LAST $SEC 1
J 0
(-7100 3125);
DISPLAY 0.680851 (-7100 3125);
PAINT MONO (-7100 3125);
DISPLAY INVISIBLE (-7100 3125);
FORCEPROP 2 LAST CDS_SEC 1
J 0
(-7100 3125);
DISPLAY 1.021277 (-7100 3125);
DISPLAY INVISIBLE (-7100 3125);
FORCEPROP 1 LASTPIN (-7150 3025) $PN 1
J 0
(-7140 3005);
DISPLAY 0.489362 (-7140 3005);
FORCEPROP 1 LASTPIN (-7150 2825) $PN 2
J 0
(-7140 2805);
DISPLAY 0.489362 (-7140 2805);
FORCEPROP 1 LAST MATERIAL X6S
J 0
(-7100 2825);
DISPLAY 0.489362 (-7100 2825);
PAINT SKYBLUE (-7100 2825);
FORCEPROP 1 LAST TOLERANCE 20%
J 0
(-7100 2875);
DISPLAY 0.489362 (-7100 2875);
PAINT SKYBLUE (-7100 2875);
FORCEPROP 1 LAST VALUE 22UF
J 0
(-7100 2975);
DISPLAY 0.489362 (-7100 2975);
PAINT SKYBLUE (-7100 2975);
FORCEPROP 1 LAST VOLTAGE 4V
J 0
(-7100 2925);
DISPLAY 0.489362 (-7100 2925);
PAINT SKYBLUE (-7100 2925);
FORCEPROP 1 LAST PACK_TYPE C0402
J 0
(-7100 2725);
DISPLAY 0.489362 (-7100 2725);
PAINT SKYBLUE (-7100 2725);
FORCEPROP 2 LAST CDS_LIB pure_quanta
J 0
(-7150 2925);
PAINT MONO (-7150 2925);
DISPLAY INVISIBLE (-7150 2925);
FORCEPROP 1 LAST PATH I30
J 0
(-7100 3075);
DISPLAY 0.978723 (-7100 3075);
PAINT WHITE (-7100 3075);
DISPLAY INVISIBLE (-7100 3075);
FORCEPROP 1 LAST PART_NUMBER CH622KMEB02
J 0
(-7100 2775);
DISPLAY 0.489362 (-7100 2775);
PAINT SKYBLUE (-7100 2775);
DISPLAY INVISIBLE (-7100 2775);
FORCEADD Q_CAP..1
(-7600 3725);
FORCEPROP 1 LAST LOCATION C2319
J 0
(-7550 3825);
DISPLAY 0.489362 (-7550 3825);
PAINT SKYBLUE (-7550 3825);
FORCEPROP 2 LAST $SEC 1
J 0
(-7550 3925);
DISPLAY 0.680851 (-7550 3925);
PAINT MONO (-7550 3925);
DISPLAY INVISIBLE (-7550 3925);
FORCEPROP 2 LAST CDS_SEC 1
J 0
(-7550 3925);
DISPLAY 1.021277 (-7550 3925);
DISPLAY INVISIBLE (-7550 3925);
FORCEPROP 1 LASTPIN (-7600 3825) $PN 1
J 0
(-7590 3805);
DISPLAY 0.489362 (-7590 3805);
FORCEPROP 1 LASTPIN (-7600 3625) $PN 2
J 0
(-7590 3605);
DISPLAY 0.489362 (-7590 3605);
FORCEPROP 1 LAST MATERIAL X6S
J 0
(-7550 3625);
DISPLAY 0.489362 (-7550 3625);
PAINT SKYBLUE (-7550 3625);
FORCEPROP 1 LAST TOLERANCE 20%
J 0
(-7550 3675);
DISPLAY 0.489362 (-7550 3675);
PAINT SKYBLUE (-7550 3675);
FORCEPROP 1 LAST VALUE 22UF
J 0
(-7550 3775);
DISPLAY 0.489362 (-7550 3775);
PAINT SKYBLUE (-7550 3775);
FORCEPROP 1 LAST VOLTAGE 4V
J 0
(-7550 3725);
DISPLAY 0.489362 (-7550 3725);
PAINT SKYBLUE (-7550 3725);
FORCEPROP 1 LAST PACK_TYPE C0402
J 0
(-7550 3525);
DISPLAY 0.489362 (-7550 3525);
PAINT SKYBLUE (-7550 3525);
FORCEPROP 2 LAST CDS_LIB pure_quanta
J 0
(-7600 3725);
PAINT MONO (-7600 3725);
DISPLAY INVISIBLE (-7600 3725);
FORCEPROP 1 LAST PATH I31
J 0
(-7550 3875);
DISPLAY 0.978723 (-7550 3875);
PAINT WHITE (-7550 3875);
DISPLAY INVISIBLE (-7550 3875);
FORCEPROP 1 LAST PART_NUMBER CH622KMEB02
J 0
(-7550 3575);
DISPLAY 0.489362 (-7550 3575);
PAINT SKYBLUE (-7550 3575);
DISPLAY INVISIBLE (-7550 3575);
FORCEADD Q_CAP..1
(-7150 3725);
FORCEPROP 1 LAST LOCATION C2325
J 0
(-7100 3825);
DISPLAY 0.489362 (-7100 3825);
PAINT SKYBLUE (-7100 3825);
FORCEPROP 2 LAST $SEC 1
J 0
(-7100 3925);
DISPLAY 0.680851 (-7100 3925);
PAINT MONO (-7100 3925);
DISPLAY INVISIBLE (-7100 3925);
FORCEPROP 2 LAST CDS_SEC 1
J 0
(-7100 3925);
DISPLAY 1.021277 (-7100 3925);
DISPLAY INVISIBLE (-7100 3925);
FORCEPROP 1 LASTPIN (-7150 3825) $PN 1
J 0
(-7140 3805);
DISPLAY 0.489362 (-7140 3805);
FORCEPROP 1 LASTPIN (-7150 3625) $PN 2
J 0
(-7140 3605);
DISPLAY 0.489362 (-7140 3605);
FORCEPROP 1 LAST MATERIAL X6S
J 0
(-7100 3625);
DISPLAY 0.489362 (-7100 3625);
PAINT SKYBLUE (-7100 3625);
FORCEPROP 1 LAST TOLERANCE 20%
J 0
(-7100 3675);
DISPLAY 0.489362 (-7100 3675);
PAINT SKYBLUE (-7100 3675);
FORCEPROP 1 LAST VALUE 22UF
J 0
(-7100 3775);
DISPLAY 0.489362 (-7100 3775);
PAINT SKYBLUE (-7100 3775);
FORCEPROP 1 LAST VOLTAGE 4V
J 0
(-7100 3725);
DISPLAY 0.489362 (-7100 3725);
PAINT SKYBLUE (-7100 3725);
FORCEPROP 1 LAST PACK_TYPE C0402
J 0
(-7100 3525);
DISPLAY 0.489362 (-7100 3525);
PAINT SKYBLUE (-7100 3525);
FORCEPROP 2 LAST CDS_LIB pure_quanta
J 0
(-7150 3725);
PAINT MONO (-7150 3725);
DISPLAY INVISIBLE (-7150 3725);
FORCEPROP 1 LAST PATH I32
J 0
(-7100 3875);
DISPLAY 0.978723 (-7100 3875);
PAINT WHITE (-7100 3875);
DISPLAY INVISIBLE (-7100 3875);
FORCEPROP 1 LAST PART_NUMBER CH622KMEB02
J 0
(-7100 3575);
DISPLAY 0.489362 (-7100 3575);
PAINT SKYBLUE (-7100 3575);
DISPLAY INVISIBLE (-7100 3575);
FORCEADD Q_CAP..1
(-6700 2125);
FORCEPROP 1 LAST LOCATION C2333
J 0
(-6650 2225);
DISPLAY 0.489362 (-6650 2225);
PAINT SKYBLUE (-6650 2225);
FORCEPROP 2 LAST $SEC 1
J 0
(-6650 2325);
DISPLAY 0.680851 (-6650 2325);
PAINT MONO (-6650 2325);
DISPLAY INVISIBLE (-6650 2325);
FORCEPROP 2 LAST CDS_SEC 1
J 0
(-6650 2325);
DISPLAY 1.021277 (-6650 2325);
DISPLAY INVISIBLE (-6650 2325);
FORCEPROP 1 LASTPIN (-6700 2225) $PN 1
J 0
(-6690 2205);
DISPLAY 0.489362 (-6690 2205);
FORCEPROP 1 LASTPIN (-6700 2025) $PN 2
J 0
(-6690 2005);
DISPLAY 0.489362 (-6690 2005);
FORCEPROP 1 LAST MATERIAL X6S
J 0
(-6650 2025);
DISPLAY 0.489362 (-6650 2025);
PAINT SKYBLUE (-6650 2025);
FORCEPROP 1 LAST TOLERANCE 20%
J 0
(-6650 2075);
DISPLAY 0.489362 (-6650 2075);
PAINT SKYBLUE (-6650 2075);
FORCEPROP 1 LAST VALUE 22UF
J 0
(-6650 2175);
DISPLAY 0.489362 (-6650 2175);
PAINT SKYBLUE (-6650 2175);
FORCEPROP 1 LAST VOLTAGE 4V
J 0
(-6650 2125);
DISPLAY 0.489362 (-6650 2125);
PAINT SKYBLUE (-6650 2125);
FORCEPROP 1 LAST PACK_TYPE C0402
J 0
(-6650 1925);
DISPLAY 0.489362 (-6650 1925);
PAINT SKYBLUE (-6650 1925);
FORCEPROP 2 LAST CDS_LIB pure_quanta
J 0
(-6700 2125);
PAINT MONO (-6700 2125);
DISPLAY INVISIBLE (-6700 2125);
FORCEPROP 1 LAST PATH I33
J 0
(-6650 2275);
DISPLAY 0.978723 (-6650 2275);
PAINT WHITE (-6650 2275);
DISPLAY INVISIBLE (-6650 2275);
FORCEPROP 1 LAST PART_NUMBER CH622KMEB02
J 0
(-6650 1975);
DISPLAY 0.489362 (-6650 1975);
PAINT SKYBLUE (-6650 1975);
DISPLAY INVISIBLE (-6650 1975);
FORCEADD Q_CAP..1
(-6250 2125);
FORCEPROP 1 LAST LOCATION C2338
J 0
(-6200 2225);
DISPLAY 0.489362 (-6200 2225);
PAINT SKYBLUE (-6200 2225);
FORCEPROP 2 LAST $SEC 1
J 0
(-6200 2325);
DISPLAY 0.680851 (-6200 2325);
PAINT MONO (-6200 2325);
DISPLAY INVISIBLE (-6200 2325);
FORCEPROP 2 LAST CDS_SEC 1
J 0
(-6200 2325);
DISPLAY 1.021277 (-6200 2325);
DISPLAY INVISIBLE (-6200 2325);
FORCEPROP 1 LASTPIN (-6250 2225) $PN 1
J 0
(-6240 2205);
DISPLAY 0.489362 (-6240 2205);
FORCEPROP 1 LASTPIN (-6250 2025) $PN 2
J 0
(-6240 2005);
DISPLAY 0.489362 (-6240 2005);
FORCEPROP 1 LAST MATERIAL X6S
J 0
(-6200 2025);
DISPLAY 0.489362 (-6200 2025);
PAINT SKYBLUE (-6200 2025);
FORCEPROP 1 LAST TOLERANCE 20%
J 0
(-6200 2075);
DISPLAY 0.489362 (-6200 2075);
PAINT SKYBLUE (-6200 2075);
FORCEPROP 1 LAST VALUE 22UF
J 0
(-6200 2175);
DISPLAY 0.489362 (-6200 2175);
PAINT SKYBLUE (-6200 2175);
FORCEPROP 1 LAST VOLTAGE 4V
J 0
(-6200 2125);
DISPLAY 0.489362 (-6200 2125);
PAINT SKYBLUE (-6200 2125);
FORCEPROP 1 LAST PACK_TYPE C0402
J 0
(-6200 1925);
DISPLAY 0.489362 (-6200 1925);
PAINT SKYBLUE (-6200 1925);
FORCEPROP 2 LAST CDS_LIB pure_quanta
J 0
(-6250 2125);
PAINT MONO (-6250 2125);
DISPLAY INVISIBLE (-6250 2125);
FORCEPROP 1 LAST PATH I34
J 0
(-6200 2275);
DISPLAY 0.978723 (-6200 2275);
PAINT WHITE (-6200 2275);
DISPLAY INVISIBLE (-6200 2275);
FORCEPROP 1 LAST PART_NUMBER CH622KMEB02
J 0
(-6200 1975);
DISPLAY 0.489362 (-6200 1975);
PAINT SKYBLUE (-6200 1975);
DISPLAY INVISIBLE (-6200 1975);
FORCEADD Q_CAP..1
(-6700 2925);
FORCEPROP 1 LAST LOCATION C2332
J 0
(-6650 3025);
DISPLAY 0.489362 (-6650 3025);
PAINT SKYBLUE (-6650 3025);
FORCEPROP 2 LAST $SEC 1
J 0
(-6650 3125);
DISPLAY 0.680851 (-6650 3125);
PAINT MONO (-6650 3125);
DISPLAY INVISIBLE (-6650 3125);
FORCEPROP 2 LAST CDS_SEC 1
J 0
(-6650 3125);
DISPLAY 1.021277 (-6650 3125);
DISPLAY INVISIBLE (-6650 3125);
FORCEPROP 1 LASTPIN (-6700 3025) $PN 1
J 0
(-6690 3005);
DISPLAY 0.489362 (-6690 3005);
FORCEPROP 1 LASTPIN (-6700 2825) $PN 2
J 0
(-6690 2805);
DISPLAY 0.489362 (-6690 2805);
FORCEPROP 1 LAST MATERIAL X6S
J 0
(-6650 2825);
DISPLAY 0.489362 (-6650 2825);
PAINT SKYBLUE (-6650 2825);
FORCEPROP 1 LAST TOLERANCE 20%
J 0
(-6650 2875);
DISPLAY 0.489362 (-6650 2875);
PAINT SKYBLUE (-6650 2875);
FORCEPROP 1 LAST VALUE 22UF
J 0
(-6650 2975);
DISPLAY 0.489362 (-6650 2975);
PAINT SKYBLUE (-6650 2975);
FORCEPROP 1 LAST VOLTAGE 4V
J 0
(-6650 2925);
DISPLAY 0.489362 (-6650 2925);
PAINT SKYBLUE (-6650 2925);
FORCEPROP 1 LAST PACK_TYPE C0402
J 0
(-6650 2725);
DISPLAY 0.489362 (-6650 2725);
PAINT SKYBLUE (-6650 2725);
FORCEPROP 2 LAST CDS_LIB pure_quanta
J 0
(-6700 2925);
PAINT MONO (-6700 2925);
DISPLAY INVISIBLE (-6700 2925);
FORCEPROP 1 LAST PATH I35
J 0
(-6650 3075);
DISPLAY 0.978723 (-6650 3075);
PAINT WHITE (-6650 3075);
DISPLAY INVISIBLE (-6650 3075);
FORCEPROP 1 LAST PART_NUMBER CH622KMEB02
J 0
(-6650 2775);
DISPLAY 0.489362 (-6650 2775);
PAINT SKYBLUE (-6650 2775);
DISPLAY INVISIBLE (-6650 2775);
FORCEADD Q_CAP..1
(-6700 3725);
FORCEPROP 1 LAST LOCATION C2331
J 0
(-6650 3825);
DISPLAY 0.489362 (-6650 3825);
PAINT SKYBLUE (-6650 3825);
FORCEPROP 2 LAST $SEC 1
J 0
(-6650 3925);
DISPLAY 0.680851 (-6650 3925);
PAINT MONO (-6650 3925);
DISPLAY INVISIBLE (-6650 3925);
FORCEPROP 2 LAST CDS_SEC 1
J 0
(-6650 3925);
DISPLAY 1.021277 (-6650 3925);
DISPLAY INVISIBLE (-6650 3925);
FORCEPROP 1 LASTPIN (-6700 3825) $PN 1
J 0
(-6690 3805);
DISPLAY 0.489362 (-6690 3805);
FORCEPROP 1 LASTPIN (-6700 3625) $PN 2
J 0
(-6690 3605);
DISPLAY 0.489362 (-6690 3605);
FORCEPROP 1 LAST MATERIAL X6S
J 0
(-6650 3625);
DISPLAY 0.489362 (-6650 3625);
PAINT SKYBLUE (-6650 3625);
FORCEPROP 1 LAST TOLERANCE 20%
J 0
(-6650 3675);
DISPLAY 0.489362 (-6650 3675);
PAINT SKYBLUE (-6650 3675);
FORCEPROP 1 LAST VALUE 22UF
J 0
(-6650 3775);
DISPLAY 0.489362 (-6650 3775);
PAINT SKYBLUE (-6650 3775);
FORCEPROP 1 LAST VOLTAGE 4V
J 0
(-6650 3725);
DISPLAY 0.489362 (-6650 3725);
PAINT SKYBLUE (-6650 3725);
FORCEPROP 1 LAST PACK_TYPE C0402
J 0
(-6650 3525);
DISPLAY 0.489362 (-6650 3525);
PAINT SKYBLUE (-6650 3525);
FORCEPROP 2 LAST CDS_LIB pure_quanta
J 0
(-6700 3725);
PAINT MONO (-6700 3725);
DISPLAY INVISIBLE (-6700 3725);
FORCEPROP 1 LAST PATH I36
J 0
(-6650 3875);
DISPLAY 0.978723 (-6650 3875);
PAINT WHITE (-6650 3875);
DISPLAY INVISIBLE (-6650 3875);
FORCEPROP 1 LAST PART_NUMBER CH622KMEB02
J 0
(-6650 3575);
DISPLAY 0.489362 (-6650 3575);
PAINT SKYBLUE (-6650 3575);
DISPLAY INVISIBLE (-6650 3575);
FORCEADD Q_CAP..1
(-6250 2925);
FORCEPROP 1 LAST LOCATION C2337
J 0
(-6200 3025);
DISPLAY 0.489362 (-6200 3025);
PAINT SKYBLUE (-6200 3025);
FORCEPROP 2 LAST $SEC 1
J 0
(-6200 3125);
DISPLAY 0.680851 (-6200 3125);
PAINT MONO (-6200 3125);
DISPLAY INVISIBLE (-6200 3125);
FORCEPROP 2 LAST CDS_SEC 1
J 0
(-6200 3125);
DISPLAY 1.021277 (-6200 3125);
DISPLAY INVISIBLE (-6200 3125);
FORCEPROP 1 LASTPIN (-6250 3025) $PN 1
J 0
(-6240 3005);
DISPLAY 0.489362 (-6240 3005);
FORCEPROP 1 LASTPIN (-6250 2825) $PN 2
J 0
(-6240 2805);
DISPLAY 0.489362 (-6240 2805);
FORCEPROP 1 LAST MATERIAL X6S
J 0
(-6200 2825);
DISPLAY 0.489362 (-6200 2825);
PAINT SKYBLUE (-6200 2825);
FORCEPROP 1 LAST TOLERANCE 20%
J 0
(-6200 2875);
DISPLAY 0.489362 (-6200 2875);
PAINT SKYBLUE (-6200 2875);
FORCEPROP 1 LAST VALUE 22UF
J 0
(-6200 2975);
DISPLAY 0.489362 (-6200 2975);
PAINT SKYBLUE (-6200 2975);
FORCEPROP 1 LAST VOLTAGE 4V
J 0
(-6200 2925);
DISPLAY 0.489362 (-6200 2925);
PAINT SKYBLUE (-6200 2925);
FORCEPROP 1 LAST PACK_TYPE C0402
J 0
(-6200 2725);
DISPLAY 0.489362 (-6200 2725);
PAINT SKYBLUE (-6200 2725);
FORCEPROP 2 LAST CDS_LIB pure_quanta
J 0
(-6250 2925);
PAINT MONO (-6250 2925);
DISPLAY INVISIBLE (-6250 2925);
FORCEPROP 1 LAST PATH I37
J 0
(-6200 3075);
DISPLAY 0.978723 (-6200 3075);
PAINT WHITE (-6200 3075);
DISPLAY INVISIBLE (-6200 3075);
FORCEPROP 1 LAST PART_NUMBER CH622KMEB02
J 0
(-6200 2775);
DISPLAY 0.489362 (-6200 2775);
PAINT SKYBLUE (-6200 2775);
DISPLAY INVISIBLE (-6200 2775);
FORCEADD Q_CAP..1
(-6250 3725);
FORCEPROP 1 LAST LOCATION C2336
J 0
(-6200 3825);
DISPLAY 0.489362 (-6200 3825);
PAINT SKYBLUE (-6200 3825);
FORCEPROP 2 LAST $SEC 1
J 0
(-6200 3925);
DISPLAY 0.680851 (-6200 3925);
PAINT MONO (-6200 3925);
DISPLAY INVISIBLE (-6200 3925);
FORCEPROP 2 LAST CDS_SEC 1
J 0
(-6200 3925);
DISPLAY 1.021277 (-6200 3925);
DISPLAY INVISIBLE (-6200 3925);
FORCEPROP 1 LASTPIN (-6250 3825) $PN 1
J 0
(-6240 3805);
DISPLAY 0.489362 (-6240 3805);
FORCEPROP 1 LASTPIN (-6250 3625) $PN 2
J 0
(-6240 3605);
DISPLAY 0.489362 (-6240 3605);
FORCEPROP 1 LAST MATERIAL X6S
J 0
(-6200 3625);
DISPLAY 0.489362 (-6200 3625);
PAINT SKYBLUE (-6200 3625);
FORCEPROP 1 LAST TOLERANCE 20%
J 0
(-6200 3675);
DISPLAY 0.489362 (-6200 3675);
PAINT SKYBLUE (-6200 3675);
FORCEPROP 1 LAST VALUE 22UF
J 0
(-6200 3775);
DISPLAY 0.489362 (-6200 3775);
PAINT SKYBLUE (-6200 3775);
FORCEPROP 1 LAST VOLTAGE 4V
J 0
(-6200 3725);
DISPLAY 0.489362 (-6200 3725);
PAINT SKYBLUE (-6200 3725);
FORCEPROP 1 LAST PACK_TYPE C0402
J 0
(-6200 3525);
DISPLAY 0.489362 (-6200 3525);
PAINT SKYBLUE (-6200 3525);
FORCEPROP 2 LAST CDS_LIB pure_quanta
J 0
(-6250 3725);
PAINT MONO (-6250 3725);
DISPLAY INVISIBLE (-6250 3725);
FORCEPROP 1 LAST PATH I38
J 0
(-6200 3875);
DISPLAY 0.978723 (-6200 3875);
PAINT WHITE (-6200 3875);
DISPLAY INVISIBLE (-6200 3875);
FORCEPROP 1 LAST PART_NUMBER CH622KMEB02
J 0
(-6200 3575);
DISPLAY 0.489362 (-6200 3575);
PAINT SKYBLUE (-6200 3575);
DISPLAY INVISIBLE (-6200 3575);
FORCEADD UNIVERSAL_POWER..1
(-4825 1600);
FORCEPROP 3 LASTPIN (-4825 1550) SIG_NAME PVDDCR_CPU1_P1\g
J 0
(-4815 1560);
DISPLAY 0.659574 (-4815 1560);
PAINT MONO (-4815 1560);
DISPLAY INVISIBLE (-4815 1560);
FORCEPROP 1 LAST HDL_POWER PVDDCR_CPU1_P1
J 1
(-4825 1650);
DISPLAY 0.489362 (-4825 1650);
PAINT GREEN (-4825 1650);
FORCEPROP 2 LAST CDS_LIB pure_quanta_power
J 0
(-4825 1600);
DISPLAY INVISIBLE (-4825 1600);
FORCEPROP 1 LAST PATH I39
J 0
(-4775 1625);
DISPLAY 0.872340 (-4775 1625);
PAINT AQUA (-4775 1625);
DISPLAY INVISIBLE (-4775 1625);
FORCEADD Q_CAP..1
(-8500 1325);
FORCEPROP 1 LAST LOCATION C2310
J 0
(-8450 1425);
DISPLAY 0.489362 (-8450 1425);
PAINT SKYBLUE (-8450 1425);
FORCEPROP 2 LAST $SEC 1
J 0
(-8450 1525);
DISPLAY 0.680851 (-8450 1525);
PAINT MONO (-8450 1525);
DISPLAY INVISIBLE (-8450 1525);
FORCEPROP 2 LAST CDS_SEC 1
J 0
(-8450 1525);
DISPLAY 1.021277 (-8450 1525);
DISPLAY INVISIBLE (-8450 1525);
FORCEPROP 1 LASTPIN (-8500 1425) $PN 1
J 0
(-8490 1405);
DISPLAY 0.489362 (-8490 1405);
FORCEPROP 1 LASTPIN (-8500 1225) $PN 2
J 0
(-8490 1205);
DISPLAY 0.489362 (-8490 1205);
FORCEPROP 1 LAST MATERIAL X6S
J 0
(-8450 1225);
DISPLAY 0.489362 (-8450 1225);
PAINT SKYBLUE (-8450 1225);
FORCEPROP 1 LAST TOLERANCE 20%
J 0
(-8450 1275);
DISPLAY 0.489362 (-8450 1275);
PAINT SKYBLUE (-8450 1275);
FORCEPROP 1 LAST VALUE 22UF
J 0
(-8450 1375);
DISPLAY 0.489362 (-8450 1375);
PAINT SKYBLUE (-8450 1375);
FORCEPROP 1 LAST VOLTAGE 4V
J 0
(-8450 1325);
DISPLAY 0.489362 (-8450 1325);
PAINT SKYBLUE (-8450 1325);
FORCEPROP 1 LAST PACK_TYPE C0402
J 0
(-8450 1125);
DISPLAY 0.489362 (-8450 1125);
PAINT SKYBLUE (-8450 1125);
FORCEPROP 2 LAST CDS_LIB pure_quanta
J 0
(-8500 1325);
PAINT MONO (-8500 1325);
DISPLAY INVISIBLE (-8500 1325);
FORCEPROP 1 LAST PATH I4
J 0
(-8450 1475);
DISPLAY 0.978723 (-8450 1475);
PAINT WHITE (-8450 1475);
DISPLAY INVISIBLE (-8450 1475);
FORCEPROP 1 LAST PART_NUMBER CH622KMEB02
J 0
(-8450 1175);
DISPLAY 0.489362 (-8450 1175);
PAINT SKYBLUE (-8450 1175);
DISPLAY INVISIBLE (-8450 1175);
FORCEADD Q_CAP..1
(-4825 1325);
FORCEPROP 1 LAST LOCATION C2354
J 0
(-4775 1425);
DISPLAY 0.489362 (-4775 1425);
PAINT SKYBLUE (-4775 1425);
FORCEPROP 2 LAST $SEC 1
J 0
(-4775 1525);
DISPLAY 0.680851 (-4775 1525);
PAINT MONO (-4775 1525);
DISPLAY INVISIBLE (-4775 1525);
FORCEPROP 2 LAST CDS_SEC 1
J 0
(-4775 1525);
DISPLAY 1.021277 (-4775 1525);
DISPLAY INVISIBLE (-4775 1525);
FORCEPROP 1 LASTPIN (-4825 1425) $PN 1
J 0
(-4815 1405);
DISPLAY 0.489362 (-4815 1405);
FORCEPROP 1 LASTPIN (-4825 1225) $PN 2
J 0
(-4815 1205);
DISPLAY 0.489362 (-4815 1205);
FORCEPROP 1 LAST MATERIAL X6S
J 0
(-4775 1225);
DISPLAY 0.489362 (-4775 1225);
PAINT SKYBLUE (-4775 1225);
FORCEPROP 1 LAST TOLERANCE 20%
J 0
(-4775 1275);
DISPLAY 0.489362 (-4775 1275);
PAINT SKYBLUE (-4775 1275);
FORCEPROP 1 LAST VALUE 22UF
J 0
(-4775 1375);
DISPLAY 0.489362 (-4775 1375);
PAINT SKYBLUE (-4775 1375);
FORCEPROP 1 LAST VOLTAGE 4V
J 0
(-4775 1325);
DISPLAY 0.489362 (-4775 1325);
PAINT SKYBLUE (-4775 1325);
FORCEPROP 1 LAST PACK_TYPE C0402
J 0
(-4775 1125);
DISPLAY 0.489362 (-4775 1125);
PAINT SKYBLUE (-4775 1125);
FORCEPROP 2 LAST CDS_LIB pure_quanta
J 0
(-4825 1325);
PAINT MONO (-4825 1325);
DISPLAY INVISIBLE (-4825 1325);
FORCEPROP 1 LAST PATH I40
J 0
(-4775 1475);
DISPLAY 0.978723 (-4775 1475);
PAINT WHITE (-4775 1475);
DISPLAY INVISIBLE (-4775 1475);
FORCEPROP 1 LAST PART_NUMBER CH622KMEB02
J 0
(-4775 1175);
DISPLAY 0.489362 (-4775 1175);
PAINT SKYBLUE (-4775 1175);
DISPLAY INVISIBLE (-4775 1175);
FORCEADD Q_CAP..1
(-4375 1325);
FORCEPROP 1 LAST LOCATION C2360
J 0
(-4325 1425);
DISPLAY 0.489362 (-4325 1425);
PAINT SKYBLUE (-4325 1425);
FORCEPROP 2 LAST $SEC 1
J 0
(-4325 1525);
DISPLAY 0.680851 (-4325 1525);
PAINT MONO (-4325 1525);
DISPLAY INVISIBLE (-4325 1525);
FORCEPROP 2 LAST CDS_SEC 1
J 0
(-4325 1525);
DISPLAY 1.021277 (-4325 1525);
DISPLAY INVISIBLE (-4325 1525);
FORCEPROP 1 LASTPIN (-4375 1425) $PN 1
J 0
(-4365 1405);
DISPLAY 0.489362 (-4365 1405);
FORCEPROP 1 LASTPIN (-4375 1225) $PN 2
J 0
(-4365 1205);
DISPLAY 0.489362 (-4365 1205);
FORCEPROP 1 LAST MATERIAL X6S
J 0
(-4325 1225);
DISPLAY 0.489362 (-4325 1225);
PAINT SKYBLUE (-4325 1225);
FORCEPROP 1 LAST TOLERANCE 20%
J 0
(-4325 1275);
DISPLAY 0.489362 (-4325 1275);
PAINT SKYBLUE (-4325 1275);
FORCEPROP 1 LAST VALUE 22UF
J 0
(-4325 1375);
DISPLAY 0.489362 (-4325 1375);
PAINT SKYBLUE (-4325 1375);
FORCEPROP 1 LAST VOLTAGE 4V
J 0
(-4325 1325);
DISPLAY 0.489362 (-4325 1325);
PAINT SKYBLUE (-4325 1325);
FORCEPROP 1 LAST PACK_TYPE C0402
J 0
(-4325 1125);
DISPLAY 0.489362 (-4325 1125);
PAINT SKYBLUE (-4325 1125);
FORCEPROP 2 LAST CDS_LIB pure_quanta
J 0
(-4375 1325);
PAINT MONO (-4375 1325);
DISPLAY INVISIBLE (-4375 1325);
FORCEPROP 1 LAST PATH I41
J 0
(-4325 1475);
DISPLAY 0.978723 (-4325 1475);
PAINT WHITE (-4325 1475);
DISPLAY INVISIBLE (-4325 1475);
FORCEPROP 1 LAST PART_NUMBER CH622KMEB02
J 0
(-4325 1175);
DISPLAY 0.489362 (-4325 1175);
PAINT SKYBLUE (-4325 1175);
DISPLAY INVISIBLE (-4325 1175);
FORCEADD Q_CAP..1
(-5800 2125);
FORCEPROP 1 LAST LOCATION C2343
J 0
(-5750 2225);
DISPLAY 0.489362 (-5750 2225);
PAINT SKYBLUE (-5750 2225);
FORCEPROP 2 LAST $SEC 1
J 0
(-5750 2325);
DISPLAY 0.680851 (-5750 2325);
PAINT MONO (-5750 2325);
DISPLAY INVISIBLE (-5750 2325);
FORCEPROP 2 LAST CDS_SEC 1
J 0
(-5750 2325);
DISPLAY 1.021277 (-5750 2325);
DISPLAY INVISIBLE (-5750 2325);
FORCEPROP 1 LASTPIN (-5800 2225) $PN 1
J 0
(-5790 2205);
DISPLAY 0.489362 (-5790 2205);
FORCEPROP 1 LASTPIN (-5800 2025) $PN 2
J 0
(-5790 2005);
DISPLAY 0.489362 (-5790 2005);
FORCEPROP 1 LAST MATERIAL X6S
J 0
(-5750 2025);
DISPLAY 0.489362 (-5750 2025);
PAINT SKYBLUE (-5750 2025);
FORCEPROP 1 LAST TOLERANCE 20%
J 0
(-5750 2075);
DISPLAY 0.489362 (-5750 2075);
PAINT SKYBLUE (-5750 2075);
FORCEPROP 1 LAST VALUE 22UF
J 0
(-5750 2175);
DISPLAY 0.489362 (-5750 2175);
PAINT SKYBLUE (-5750 2175);
FORCEPROP 1 LAST VOLTAGE 4V
J 0
(-5750 2125);
DISPLAY 0.489362 (-5750 2125);
PAINT SKYBLUE (-5750 2125);
FORCEPROP 1 LAST PACK_TYPE C0402
J 0
(-5750 1925);
DISPLAY 0.489362 (-5750 1925);
PAINT SKYBLUE (-5750 1925);
FORCEPROP 2 LAST CDS_LIB pure_quanta
J 0
(-5800 2125);
PAINT MONO (-5800 2125);
DISPLAY INVISIBLE (-5800 2125);
FORCEPROP 1 LAST PATH I42
J 0
(-5750 2275);
DISPLAY 0.978723 (-5750 2275);
PAINT WHITE (-5750 2275);
DISPLAY INVISIBLE (-5750 2275);
FORCEPROP 1 LAST PART_NUMBER CH622KMEB02
J 0
(-5750 1975);
DISPLAY 0.489362 (-5750 1975);
PAINT SKYBLUE (-5750 1975);
DISPLAY INVISIBLE (-5750 1975);
FORCEADD UNIVERSAL_GND..1
(-5400 1750);
FORCEPROP 3 LASTPIN (-5400 1800) SIG_NAME GND\g
J 0
(-5390 1810);
DISPLAY 0.659574 (-5390 1810);
PAINT MONO (-5390 1810);
DISPLAY INVISIBLE (-5390 1810);
FORCEPROP 2 LAST CDS_LIB pure_quanta_power
J 0
(-5400 1750);
PAINT MONO (-5400 1750);
DISPLAY INVISIBLE (-5400 1750);
FORCEPROP 1 LAST HDL_POWER GND
J 1
(-5375 1675);
DISPLAY 0.872340 (-5375 1675);
PAINT GREEN (-5375 1675);
DISPLAY INVISIBLE (-5375 1675);
FORCEPROP 1 LAST PATH I43
J 0
(-5325 1750);
DISPLAY 0.872340 (-5325 1750);
PAINT AQUA (-5325 1750);
DISPLAY INVISIBLE (-5325 1750);
FORCEADD Q_CAP..1
(-5400 2125);
FORCEPROP 1 LAST LOCATION C2348
J 0
(-5350 2225);
DISPLAY 0.489362 (-5350 2225);
PAINT SKYBLUE (-5350 2225);
FORCEPROP 2 LAST $SEC 1
J 0
(-5350 2325);
DISPLAY 0.680851 (-5350 2325);
PAINT MONO (-5350 2325);
DISPLAY INVISIBLE (-5350 2325);
FORCEPROP 2 LAST CDS_SEC 1
J 0
(-5350 2325);
DISPLAY 1.021277 (-5350 2325);
DISPLAY INVISIBLE (-5350 2325);
FORCEPROP 1 LASTPIN (-5400 2225) $PN 1
J 0
(-5390 2205);
DISPLAY 0.489362 (-5390 2205);
FORCEPROP 1 LASTPIN (-5400 2025) $PN 2
J 0
(-5390 2005);
DISPLAY 0.489362 (-5390 2005);
FORCEPROP 1 LAST MATERIAL X6S
J 0
(-5350 2025);
DISPLAY 0.489362 (-5350 2025);
PAINT SKYBLUE (-5350 2025);
FORCEPROP 1 LAST TOLERANCE 20%
J 0
(-5350 2075);
DISPLAY 0.489362 (-5350 2075);
PAINT SKYBLUE (-5350 2075);
FORCEPROP 1 LAST VALUE 22UF
J 0
(-5350 2175);
DISPLAY 0.489362 (-5350 2175);
PAINT SKYBLUE (-5350 2175);
FORCEPROP 1 LAST VOLTAGE 4V
J 0
(-5350 2125);
DISPLAY 0.489362 (-5350 2125);
PAINT SKYBLUE (-5350 2125);
FORCEPROP 1 LAST PACK_TYPE C0402
J 0
(-5350 1925);
DISPLAY 0.489362 (-5350 1925);
PAINT SKYBLUE (-5350 1925);
FORCEPROP 2 LAST CDS_LIB pure_quanta
J 0
(-5400 2125);
PAINT MONO (-5400 2125);
DISPLAY INVISIBLE (-5400 2125);
FORCEPROP 1 LAST PATH I44
J 0
(-5350 2275);
DISPLAY 0.978723 (-5350 2275);
PAINT WHITE (-5350 2275);
DISPLAY INVISIBLE (-5350 2275);
FORCEPROP 1 LAST PART_NUMBER CH622KMEB02
J 0
(-5350 1975);
DISPLAY 0.489362 (-5350 1975);
PAINT SKYBLUE (-5350 1975);
DISPLAY INVISIBLE (-5350 1975);
FORCEADD UNIVERSAL_GND..1
(-5400 2550);
FORCEPROP 3 LASTPIN (-5400 2600) SIG_NAME GND\g
J 0
(-5390 2610);
DISPLAY 0.659574 (-5390 2610);
PAINT MONO (-5390 2610);
DISPLAY INVISIBLE (-5390 2610);
FORCEPROP 2 LAST CDS_LIB pure_quanta_power
J 0
(-5400 2550);
PAINT MONO (-5400 2550);
DISPLAY INVISIBLE (-5400 2550);
FORCEPROP 1 LAST HDL_POWER GND
J 1
(-5375 2475);
DISPLAY 0.872340 (-5375 2475);
PAINT GREEN (-5375 2475);
DISPLAY INVISIBLE (-5375 2475);
FORCEPROP 1 LAST PATH I45
J 0
(-5325 2550);
DISPLAY 0.872340 (-5325 2550);
PAINT AQUA (-5325 2550);
DISPLAY INVISIBLE (-5325 2550);
FORCEADD Q_CAP..1
(-5800 2925);
FORCEPROP 1 LAST LOCATION C2342
J 0
(-5750 3025);
DISPLAY 0.489362 (-5750 3025);
PAINT SKYBLUE (-5750 3025);
FORCEPROP 2 LAST $SEC 1
J 0
(-5750 3125);
DISPLAY 0.680851 (-5750 3125);
PAINT MONO (-5750 3125);
DISPLAY INVISIBLE (-5750 3125);
FORCEPROP 2 LAST CDS_SEC 1
J 0
(-5750 3125);
DISPLAY 1.021277 (-5750 3125);
DISPLAY INVISIBLE (-5750 3125);
FORCEPROP 1 LASTPIN (-5800 3025) $PN 1
J 0
(-5790 3005);
DISPLAY 0.489362 (-5790 3005);
FORCEPROP 1 LASTPIN (-5800 2825) $PN 2
J 0
(-5790 2805);
DISPLAY 0.489362 (-5790 2805);
FORCEPROP 1 LAST MATERIAL X6S
J 0
(-5750 2825);
DISPLAY 0.489362 (-5750 2825);
PAINT SKYBLUE (-5750 2825);
FORCEPROP 1 LAST TOLERANCE 20%
J 0
(-5750 2875);
DISPLAY 0.489362 (-5750 2875);
PAINT SKYBLUE (-5750 2875);
FORCEPROP 1 LAST VALUE 22UF
J 0
(-5750 2975);
DISPLAY 0.489362 (-5750 2975);
PAINT SKYBLUE (-5750 2975);
FORCEPROP 1 LAST VOLTAGE 4V
J 0
(-5750 2925);
DISPLAY 0.489362 (-5750 2925);
PAINT SKYBLUE (-5750 2925);
FORCEPROP 1 LAST PACK_TYPE C0402
J 0
(-5750 2725);
DISPLAY 0.489362 (-5750 2725);
PAINT SKYBLUE (-5750 2725);
FORCEPROP 2 LAST CDS_LIB pure_quanta
J 0
(-5800 2925);
PAINT MONO (-5800 2925);
DISPLAY INVISIBLE (-5800 2925);
FORCEPROP 1 LAST PATH I46
J 0
(-5750 3075);
DISPLAY 0.978723 (-5750 3075);
PAINT WHITE (-5750 3075);
DISPLAY INVISIBLE (-5750 3075);
FORCEPROP 1 LAST PART_NUMBER CH622KMEB02
J 0
(-5750 2775);
DISPLAY 0.489362 (-5750 2775);
PAINT SKYBLUE (-5750 2775);
DISPLAY INVISIBLE (-5750 2775);
FORCEADD Q_CAP..1
(-5800 3725);
FORCEPROP 1 LAST LOCATION C2341
J 0
(-5750 3825);
DISPLAY 0.489362 (-5750 3825);
PAINT SKYBLUE (-5750 3825);
FORCEPROP 2 LAST $SEC 1
J 0
(-5750 3925);
DISPLAY 0.680851 (-5750 3925);
PAINT MONO (-5750 3925);
DISPLAY INVISIBLE (-5750 3925);
FORCEPROP 2 LAST CDS_SEC 1
J 0
(-5750 3925);
DISPLAY 1.021277 (-5750 3925);
DISPLAY INVISIBLE (-5750 3925);
FORCEPROP 1 LASTPIN (-5800 3825) $PN 1
J 0
(-5790 3805);
DISPLAY 0.489362 (-5790 3805);
FORCEPROP 1 LASTPIN (-5800 3625) $PN 2
J 0
(-5790 3605);
DISPLAY 0.489362 (-5790 3605);
FORCEPROP 1 LAST MATERIAL X6S
J 0
(-5750 3625);
DISPLAY 0.489362 (-5750 3625);
PAINT SKYBLUE (-5750 3625);
FORCEPROP 1 LAST TOLERANCE 20%
J 0
(-5750 3675);
DISPLAY 0.489362 (-5750 3675);
PAINT SKYBLUE (-5750 3675);
FORCEPROP 1 LAST VALUE 22UF
J 0
(-5750 3775);
DISPLAY 0.489362 (-5750 3775);
PAINT SKYBLUE (-5750 3775);
FORCEPROP 1 LAST VOLTAGE 4V
J 0
(-5750 3725);
DISPLAY 0.489362 (-5750 3725);
PAINT SKYBLUE (-5750 3725);
FORCEPROP 1 LAST PACK_TYPE C0402
J 0
(-5750 3525);
DISPLAY 0.489362 (-5750 3525);
PAINT SKYBLUE (-5750 3525);
FORCEPROP 2 LAST CDS_LIB pure_quanta
J 0
(-5800 3725);
PAINT MONO (-5800 3725);
DISPLAY INVISIBLE (-5800 3725);
FORCEPROP 1 LAST PATH I47
J 0
(-5750 3875);
DISPLAY 0.978723 (-5750 3875);
PAINT WHITE (-5750 3875);
DISPLAY INVISIBLE (-5750 3875);
FORCEPROP 1 LAST PART_NUMBER CH622KMEB02
J 0
(-5750 3575);
DISPLAY 0.489362 (-5750 3575);
PAINT SKYBLUE (-5750 3575);
DISPLAY INVISIBLE (-5750 3575);
FORCEADD Q_CAP..1
(-5400 2925);
FORCEPROP 1 LAST LOCATION C2347
J 0
(-5350 3025);
DISPLAY 0.489362 (-5350 3025);
PAINT SKYBLUE (-5350 3025);
FORCEPROP 2 LAST $SEC 1
J 0
(-5350 3125);
DISPLAY 0.680851 (-5350 3125);
PAINT MONO (-5350 3125);
DISPLAY INVISIBLE (-5350 3125);
FORCEPROP 2 LAST CDS_SEC 1
J 0
(-5350 3125);
DISPLAY 1.021277 (-5350 3125);
DISPLAY INVISIBLE (-5350 3125);
FORCEPROP 1 LASTPIN (-5400 3025) $PN 1
J 0
(-5390 3005);
DISPLAY 0.489362 (-5390 3005);
FORCEPROP 1 LASTPIN (-5400 2825) $PN 2
J 0
(-5390 2805);
DISPLAY 0.489362 (-5390 2805);
FORCEPROP 1 LAST MATERIAL X6S
J 0
(-5350 2825);
DISPLAY 0.489362 (-5350 2825);
PAINT SKYBLUE (-5350 2825);
FORCEPROP 1 LAST TOLERANCE 20%
J 0
(-5350 2875);
DISPLAY 0.489362 (-5350 2875);
PAINT SKYBLUE (-5350 2875);
FORCEPROP 1 LAST VALUE 22UF
J 0
(-5350 2975);
DISPLAY 0.489362 (-5350 2975);
PAINT SKYBLUE (-5350 2975);
FORCEPROP 1 LAST VOLTAGE 4V
J 0
(-5350 2925);
DISPLAY 0.489362 (-5350 2925);
PAINT SKYBLUE (-5350 2925);
FORCEPROP 1 LAST PACK_TYPE C0402
J 0
(-5350 2725);
DISPLAY 0.489362 (-5350 2725);
PAINT SKYBLUE (-5350 2725);
FORCEPROP 2 LAST CDS_LIB pure_quanta
J 0
(-5400 2925);
PAINT MONO (-5400 2925);
DISPLAY INVISIBLE (-5400 2925);
FORCEPROP 1 LAST PATH I48
J 0
(-5350 3075);
DISPLAY 0.978723 (-5350 3075);
PAINT WHITE (-5350 3075);
DISPLAY INVISIBLE (-5350 3075);
FORCEPROP 1 LAST PART_NUMBER CH622KMEB02
J 0
(-5350 2775);
DISPLAY 0.489362 (-5350 2775);
PAINT SKYBLUE (-5350 2775);
DISPLAY INVISIBLE (-5350 2775);
FORCEADD UNIVERSAL_GND..1
(-5400 3350);
FORCEPROP 3 LASTPIN (-5400 3400) SIG_NAME GND\g
J 0
(-5390 3410);
DISPLAY 0.659574 (-5390 3410);
PAINT MONO (-5390 3410);
DISPLAY INVISIBLE (-5390 3410);
FORCEPROP 2 LAST CDS_LIB pure_quanta_power
J 0
(-5400 3350);
PAINT MONO (-5400 3350);
DISPLAY INVISIBLE (-5400 3350);
FORCEPROP 1 LAST HDL_POWER GND
J 1
(-5375 3275);
DISPLAY 0.872340 (-5375 3275);
PAINT GREEN (-5375 3275);
DISPLAY INVISIBLE (-5375 3275);
FORCEPROP 1 LAST PATH I49
J 0
(-5325 3350);
DISPLAY 0.872340 (-5325 3350);
PAINT AQUA (-5325 3350);
DISPLAY INVISIBLE (-5325 3350);
FORCEADD Q_CAP..1
(-9400 2125);
FORCEPROP 1 LAST LOCATION C2297
J 0
(-9350 2225);
DISPLAY 0.489362 (-9350 2225);
PAINT SKYBLUE (-9350 2225);
FORCEPROP 2 LAST $SEC 1
J 0
(-9350 2325);
DISPLAY 0.680851 (-9350 2325);
PAINT MONO (-9350 2325);
DISPLAY INVISIBLE (-9350 2325);
FORCEPROP 2 LAST CDS_SEC 1
J 0
(-9350 2325);
DISPLAY 1.021277 (-9350 2325);
DISPLAY INVISIBLE (-9350 2325);
FORCEPROP 1 LASTPIN (-9400 2225) $PN 1
J 0
(-9390 2205);
DISPLAY 0.489362 (-9390 2205);
FORCEPROP 1 LASTPIN (-9400 2025) $PN 2
J 0
(-9390 2005);
DISPLAY 0.489362 (-9390 2005);
FORCEPROP 1 LAST MATERIAL X6S
J 0
(-9350 2025);
DISPLAY 0.489362 (-9350 2025);
PAINT SKYBLUE (-9350 2025);
FORCEPROP 1 LAST TOLERANCE 20%
J 0
(-9350 2075);
DISPLAY 0.489362 (-9350 2075);
PAINT SKYBLUE (-9350 2075);
FORCEPROP 1 LAST VALUE 22UF
J 0
(-9350 2175);
DISPLAY 0.489362 (-9350 2175);
PAINT SKYBLUE (-9350 2175);
FORCEPROP 1 LAST VOLTAGE 4V
J 0
(-9350 2125);
DISPLAY 0.489362 (-9350 2125);
PAINT SKYBLUE (-9350 2125);
FORCEPROP 1 LAST PACK_TYPE C0402
J 0
(-9350 1925);
DISPLAY 0.489362 (-9350 1925);
PAINT SKYBLUE (-9350 1925);
FORCEPROP 2 LAST CDS_LIB pure_quanta
J 0
(-9400 2125);
PAINT MONO (-9400 2125);
DISPLAY INVISIBLE (-9400 2125);
FORCEPROP 1 LAST PATH I5
J 0
(-9350 2275);
DISPLAY 0.978723 (-9350 2275);
PAINT WHITE (-9350 2275);
DISPLAY INVISIBLE (-9350 2275);
FORCEPROP 1 LAST PART_NUMBER CH622KMEB02
J 0
(-9350 1975);
DISPLAY 0.489362 (-9350 1975);
PAINT SKYBLUE (-9350 1975);
DISPLAY INVISIBLE (-9350 1975);
FORCEADD Q_CAP..1
(-5400 3725);
FORCEPROP 1 LAST LOCATION C2346
J 0
(-5350 3825);
DISPLAY 0.489362 (-5350 3825);
PAINT SKYBLUE (-5350 3825);
FORCEPROP 2 LAST $SEC 1
J 0
(-5350 3925);
DISPLAY 0.680851 (-5350 3925);
PAINT MONO (-5350 3925);
DISPLAY INVISIBLE (-5350 3925);
FORCEPROP 2 LAST CDS_SEC 1
J 0
(-5350 3925);
DISPLAY 1.021277 (-5350 3925);
DISPLAY INVISIBLE (-5350 3925);
FORCEPROP 1 LASTPIN (-5400 3825) $PN 1
J 0
(-5390 3805);
DISPLAY 0.489362 (-5390 3805);
FORCEPROP 1 LASTPIN (-5400 3625) $PN 2
J 0
(-5390 3605);
DISPLAY 0.489362 (-5390 3605);
FORCEPROP 1 LAST MATERIAL X6S
J 0
(-5350 3625);
DISPLAY 0.489362 (-5350 3625);
PAINT SKYBLUE (-5350 3625);
FORCEPROP 1 LAST TOLERANCE 20%
J 0
(-5350 3675);
DISPLAY 0.489362 (-5350 3675);
PAINT SKYBLUE (-5350 3675);
FORCEPROP 1 LAST VALUE 22UF
J 0
(-5350 3775);
DISPLAY 0.489362 (-5350 3775);
PAINT SKYBLUE (-5350 3775);
FORCEPROP 1 LAST VOLTAGE 4V
J 0
(-5350 3725);
DISPLAY 0.489362 (-5350 3725);
PAINT SKYBLUE (-5350 3725);
FORCEPROP 1 LAST PACK_TYPE C0402
J 0
(-5350 3525);
DISPLAY 0.489362 (-5350 3525);
PAINT SKYBLUE (-5350 3525);
FORCEPROP 2 LAST CDS_LIB pure_quanta
J 0
(-5400 3725);
PAINT MONO (-5400 3725);
DISPLAY INVISIBLE (-5400 3725);
FORCEPROP 1 LAST PATH I50
J 0
(-5350 3875);
DISPLAY 0.978723 (-5350 3875);
PAINT WHITE (-5350 3875);
DISPLAY INVISIBLE (-5350 3875);
FORCEPROP 1 LAST PART_NUMBER CH622KMEB02
J 0
(-5350 3575);
DISPLAY 0.489362 (-5350 3575);
PAINT SKYBLUE (-5350 3575);
DISPLAY INVISIBLE (-5350 3575);
FORCEADD Q_CAP..1
(-4825 2125);
FORCEPROP 1 LAST LOCATION C2353
J 0
(-4775 2225);
DISPLAY 0.489362 (-4775 2225);
PAINT SKYBLUE (-4775 2225);
FORCEPROP 2 LAST $SEC 1
J 0
(-4775 2325);
DISPLAY 0.680851 (-4775 2325);
PAINT MONO (-4775 2325);
DISPLAY INVISIBLE (-4775 2325);
FORCEPROP 2 LAST CDS_SEC 1
J 0
(-4775 2325);
DISPLAY 1.021277 (-4775 2325);
DISPLAY INVISIBLE (-4775 2325);
FORCEPROP 1 LASTPIN (-4825 2225) $PN 1
J 0
(-4815 2205);
DISPLAY 0.489362 (-4815 2205);
FORCEPROP 1 LASTPIN (-4825 2025) $PN 2
J 0
(-4815 2005);
DISPLAY 0.489362 (-4815 2005);
FORCEPROP 1 LAST MATERIAL X6S
J 0
(-4775 2025);
DISPLAY 0.489362 (-4775 2025);
PAINT SKYBLUE (-4775 2025);
FORCEPROP 1 LAST TOLERANCE 20%
J 0
(-4775 2075);
DISPLAY 0.489362 (-4775 2075);
PAINT SKYBLUE (-4775 2075);
FORCEPROP 1 LAST VALUE 22UF
J 0
(-4775 2175);
DISPLAY 0.489362 (-4775 2175);
PAINT SKYBLUE (-4775 2175);
FORCEPROP 1 LAST VOLTAGE 4V
J 0
(-4775 2125);
DISPLAY 0.489362 (-4775 2125);
PAINT SKYBLUE (-4775 2125);
FORCEPROP 1 LAST PACK_TYPE C0402
J 0
(-4775 1925);
DISPLAY 0.489362 (-4775 1925);
PAINT SKYBLUE (-4775 1925);
FORCEPROP 2 LAST CDS_LIB pure_quanta
J 0
(-4825 2125);
PAINT MONO (-4825 2125);
DISPLAY INVISIBLE (-4825 2125);
FORCEPROP 1 LAST PATH I51
J 0
(-4775 2275);
DISPLAY 0.978723 (-4775 2275);
PAINT WHITE (-4775 2275);
DISPLAY INVISIBLE (-4775 2275);
FORCEPROP 1 LAST PART_NUMBER CH622KMEB02
J 0
(-4775 1975);
DISPLAY 0.489362 (-4775 1975);
PAINT SKYBLUE (-4775 1975);
DISPLAY INVISIBLE (-4775 1975);
FORCEADD UNIVERSAL_POWER..1
(-4825 2400);
FORCEPROP 3 LASTPIN (-4825 2350) SIG_NAME PVDDCR_CPU1_P1\g
J 0
(-4815 2360);
DISPLAY 0.659574 (-4815 2360);
PAINT MONO (-4815 2360);
DISPLAY INVISIBLE (-4815 2360);
FORCEPROP 1 LAST HDL_POWER PVDDCR_CPU1_P1
J 1
(-4825 2450);
DISPLAY 0.489362 (-4825 2450);
PAINT GREEN (-4825 2450);
FORCEPROP 2 LAST CDS_LIB pure_quanta_power
J 0
(-4825 2400);
DISPLAY INVISIBLE (-4825 2400);
FORCEPROP 1 LAST PATH I52
J 0
(-4775 2425);
DISPLAY 0.872340 (-4775 2425);
PAINT AQUA (-4775 2425);
DISPLAY INVISIBLE (-4775 2425);
FORCEADD Q_CAP..1
(-4375 2125);
FORCEPROP 1 LAST LOCATION C2359
J 0
(-4325 2225);
DISPLAY 0.489362 (-4325 2225);
PAINT SKYBLUE (-4325 2225);
FORCEPROP 2 LAST $SEC 1
J 0
(-4325 2325);
DISPLAY 0.680851 (-4325 2325);
PAINT MONO (-4325 2325);
DISPLAY INVISIBLE (-4325 2325);
FORCEPROP 2 LAST CDS_SEC 1
J 0
(-4325 2325);
DISPLAY 1.021277 (-4325 2325);
DISPLAY INVISIBLE (-4325 2325);
FORCEPROP 1 LASTPIN (-4375 2225) $PN 1
J 0
(-4365 2205);
DISPLAY 0.489362 (-4365 2205);
FORCEPROP 1 LASTPIN (-4375 2025) $PN 2
J 0
(-4365 2005);
DISPLAY 0.489362 (-4365 2005);
FORCEPROP 1 LAST MATERIAL X6S
J 0
(-4325 2025);
DISPLAY 0.489362 (-4325 2025);
PAINT SKYBLUE (-4325 2025);
FORCEPROP 1 LAST TOLERANCE 20%
J 0
(-4325 2075);
DISPLAY 0.489362 (-4325 2075);
PAINT SKYBLUE (-4325 2075);
FORCEPROP 1 LAST VALUE 22UF
J 0
(-4325 2175);
DISPLAY 0.489362 (-4325 2175);
PAINT SKYBLUE (-4325 2175);
FORCEPROP 1 LAST VOLTAGE 4V
J 0
(-4325 2125);
DISPLAY 0.489362 (-4325 2125);
PAINT SKYBLUE (-4325 2125);
FORCEPROP 1 LAST PACK_TYPE C0402
J 0
(-4325 1925);
DISPLAY 0.489362 (-4325 1925);
PAINT SKYBLUE (-4325 1925);
FORCEPROP 2 LAST CDS_LIB pure_quanta
J 0
(-4375 2125);
PAINT MONO (-4375 2125);
DISPLAY INVISIBLE (-4375 2125);
FORCEPROP 1 LAST PATH I53
J 0
(-4325 2275);
DISPLAY 0.978723 (-4325 2275);
PAINT WHITE (-4325 2275);
DISPLAY INVISIBLE (-4325 2275);
FORCEPROP 1 LAST PART_NUMBER CH622KMEB02
J 0
(-4325 1975);
DISPLAY 0.489362 (-4325 1975);
PAINT SKYBLUE (-4325 1975);
DISPLAY INVISIBLE (-4325 1975);
FORCEADD UNIVERSAL_POWER..1
(-4825 3200);
FORCEPROP 3 LASTPIN (-4825 3150) SIG_NAME PVDDCR_CPU1_P1\g
J 0
(-4815 3160);
DISPLAY 0.659574 (-4815 3160);
PAINT MONO (-4815 3160);
DISPLAY INVISIBLE (-4815 3160);
FORCEPROP 1 LAST HDL_POWER PVDDCR_CPU1_P1
J 1
(-4825 3250);
DISPLAY 0.489362 (-4825 3250);
PAINT GREEN (-4825 3250);
FORCEPROP 2 LAST CDS_LIB pure_quanta_power
J 0
(-4825 3200);
DISPLAY INVISIBLE (-4825 3200);
FORCEPROP 1 LAST PATH I54
J 0
(-4775 3225);
DISPLAY 0.872340 (-4775 3225);
PAINT AQUA (-4775 3225);
DISPLAY INVISIBLE (-4775 3225);
FORCEADD Q_CAP..1
(-4825 2925);
FORCEPROP 1 LAST LOCATION C2352
J 0
(-4775 3025);
DISPLAY 0.489362 (-4775 3025);
PAINT SKYBLUE (-4775 3025);
FORCEPROP 2 LAST $SEC 1
J 0
(-4775 3125);
DISPLAY 0.680851 (-4775 3125);
PAINT MONO (-4775 3125);
DISPLAY INVISIBLE (-4775 3125);
FORCEPROP 2 LAST CDS_SEC 1
J 0
(-4775 3125);
DISPLAY 1.021277 (-4775 3125);
DISPLAY INVISIBLE (-4775 3125);
FORCEPROP 1 LASTPIN (-4825 3025) $PN 1
J 0
(-4815 3005);
DISPLAY 0.489362 (-4815 3005);
FORCEPROP 1 LASTPIN (-4825 2825) $PN 2
J 0
(-4815 2805);
DISPLAY 0.489362 (-4815 2805);
FORCEPROP 1 LAST MATERIAL X6S
J 0
(-4775 2825);
DISPLAY 0.489362 (-4775 2825);
PAINT SKYBLUE (-4775 2825);
FORCEPROP 1 LAST TOLERANCE 20%
J 0
(-4775 2875);
DISPLAY 0.489362 (-4775 2875);
PAINT SKYBLUE (-4775 2875);
FORCEPROP 1 LAST VALUE 22UF
J 0
(-4775 2975);
DISPLAY 0.489362 (-4775 2975);
PAINT SKYBLUE (-4775 2975);
FORCEPROP 1 LAST VOLTAGE 4V
J 0
(-4775 2925);
DISPLAY 0.489362 (-4775 2925);
PAINT SKYBLUE (-4775 2925);
FORCEPROP 1 LAST PACK_TYPE C0402
J 0
(-4775 2725);
DISPLAY 0.489362 (-4775 2725);
PAINT SKYBLUE (-4775 2725);
FORCEPROP 2 LAST CDS_LIB pure_quanta
J 0
(-4825 2925);
PAINT MONO (-4825 2925);
DISPLAY INVISIBLE (-4825 2925);
FORCEPROP 1 LAST PATH I55
J 0
(-4775 3075);
DISPLAY 0.978723 (-4775 3075);
PAINT WHITE (-4775 3075);
DISPLAY INVISIBLE (-4775 3075);
FORCEPROP 1 LAST PART_NUMBER CH622KMEB02
J 0
(-4775 2775);
DISPLAY 0.489362 (-4775 2775);
PAINT SKYBLUE (-4775 2775);
DISPLAY INVISIBLE (-4775 2775);
FORCEADD Q_CAP..1
(-4825 3725);
FORCEPROP 1 LAST LOCATION C2351
J 0
(-4775 3825);
DISPLAY 0.489362 (-4775 3825);
PAINT SKYBLUE (-4775 3825);
FORCEPROP 2 LAST $SEC 1
J 0
(-4775 3925);
DISPLAY 0.680851 (-4775 3925);
PAINT MONO (-4775 3925);
DISPLAY INVISIBLE (-4775 3925);
FORCEPROP 2 LAST CDS_SEC 1
J 0
(-4775 3925);
DISPLAY 1.021277 (-4775 3925);
DISPLAY INVISIBLE (-4775 3925);
FORCEPROP 1 LASTPIN (-4825 3825) $PN 1
J 0
(-4815 3805);
DISPLAY 0.489362 (-4815 3805);
FORCEPROP 1 LASTPIN (-4825 3625) $PN 2
J 0
(-4815 3605);
DISPLAY 0.489362 (-4815 3605);
FORCEPROP 1 LAST MATERIAL X6S
J 0
(-4775 3625);
DISPLAY 0.489362 (-4775 3625);
PAINT SKYBLUE (-4775 3625);
FORCEPROP 1 LAST TOLERANCE 20%
J 0
(-4775 3675);
DISPLAY 0.489362 (-4775 3675);
PAINT SKYBLUE (-4775 3675);
FORCEPROP 1 LAST VALUE 22UF
J 0
(-4775 3775);
DISPLAY 0.489362 (-4775 3775);
PAINT SKYBLUE (-4775 3775);
FORCEPROP 1 LAST VOLTAGE 4V
J 0
(-4775 3725);
DISPLAY 0.489362 (-4775 3725);
PAINT SKYBLUE (-4775 3725);
FORCEPROP 1 LAST PACK_TYPE C0402
J 0
(-4775 3525);
DISPLAY 0.489362 (-4775 3525);
PAINT SKYBLUE (-4775 3525);
FORCEPROP 2 LAST CDS_LIB pure_quanta
J 0
(-4825 3725);
PAINT MONO (-4825 3725);
DISPLAY INVISIBLE (-4825 3725);
FORCEPROP 1 LAST PATH I56
J 0
(-4775 3875);
DISPLAY 0.978723 (-4775 3875);
PAINT WHITE (-4775 3875);
DISPLAY INVISIBLE (-4775 3875);
FORCEPROP 1 LAST PART_NUMBER CH622KMEB02
J 0
(-4775 3575);
DISPLAY 0.489362 (-4775 3575);
PAINT SKYBLUE (-4775 3575);
DISPLAY INVISIBLE (-4775 3575);
FORCEADD Q_CAP..1
(-4375 2925);
FORCEPROP 1 LAST LOCATION C2358
J 0
(-4325 3025);
DISPLAY 0.489362 (-4325 3025);
PAINT SKYBLUE (-4325 3025);
FORCEPROP 2 LAST $SEC 1
J 0
(-4325 3125);
DISPLAY 0.680851 (-4325 3125);
PAINT MONO (-4325 3125);
DISPLAY INVISIBLE (-4325 3125);
FORCEPROP 2 LAST CDS_SEC 1
J 0
(-4325 3125);
DISPLAY 1.021277 (-4325 3125);
DISPLAY INVISIBLE (-4325 3125);
FORCEPROP 1 LASTPIN (-4375 3025) $PN 1
J 0
(-4365 3005);
DISPLAY 0.489362 (-4365 3005);
FORCEPROP 1 LASTPIN (-4375 2825) $PN 2
J 0
(-4365 2805);
DISPLAY 0.489362 (-4365 2805);
FORCEPROP 1 LAST MATERIAL X6S
J 0
(-4325 2825);
DISPLAY 0.489362 (-4325 2825);
PAINT SKYBLUE (-4325 2825);
FORCEPROP 1 LAST TOLERANCE 20%
J 0
(-4325 2875);
DISPLAY 0.489362 (-4325 2875);
PAINT SKYBLUE (-4325 2875);
FORCEPROP 1 LAST VALUE 22UF
J 0
(-4325 2975);
DISPLAY 0.489362 (-4325 2975);
PAINT SKYBLUE (-4325 2975);
FORCEPROP 1 LAST VOLTAGE 4V
J 0
(-4325 2925);
DISPLAY 0.489362 (-4325 2925);
PAINT SKYBLUE (-4325 2925);
FORCEPROP 1 LAST PACK_TYPE C0402
J 0
(-4325 2725);
DISPLAY 0.489362 (-4325 2725);
PAINT SKYBLUE (-4325 2725);
FORCEPROP 2 LAST CDS_LIB pure_quanta
J 0
(-4375 2925);
PAINT MONO (-4375 2925);
DISPLAY INVISIBLE (-4375 2925);
FORCEPROP 1 LAST PATH I57
J 0
(-4325 3075);
DISPLAY 0.978723 (-4325 3075);
PAINT WHITE (-4325 3075);
DISPLAY INVISIBLE (-4325 3075);
FORCEPROP 1 LAST PART_NUMBER CH622KMEB02
J 0
(-4325 2775);
DISPLAY 0.489362 (-4325 2775);
PAINT SKYBLUE (-4325 2775);
DISPLAY INVISIBLE (-4325 2775);
FORCEADD Q_CAP..1
(-4375 3725);
FORCEPROP 1 LAST LOCATION C2357
J 0
(-4325 3825);
DISPLAY 0.489362 (-4325 3825);
PAINT SKYBLUE (-4325 3825);
FORCEPROP 2 LAST $SEC 1
J 0
(-4325 3925);
DISPLAY 0.680851 (-4325 3925);
PAINT MONO (-4325 3925);
DISPLAY INVISIBLE (-4325 3925);
FORCEPROP 2 LAST CDS_SEC 1
J 0
(-4325 3925);
DISPLAY 1.021277 (-4325 3925);
DISPLAY INVISIBLE (-4325 3925);
FORCEPROP 1 LASTPIN (-4375 3825) $PN 1
J 0
(-4365 3805);
DISPLAY 0.489362 (-4365 3805);
FORCEPROP 1 LASTPIN (-4375 3625) $PN 2
J 0
(-4365 3605);
DISPLAY 0.489362 (-4365 3605);
FORCEPROP 1 LAST MATERIAL X6S
J 0
(-4325 3625);
DISPLAY 0.489362 (-4325 3625);
PAINT SKYBLUE (-4325 3625);
FORCEPROP 1 LAST TOLERANCE 20%
J 0
(-4325 3675);
DISPLAY 0.489362 (-4325 3675);
PAINT SKYBLUE (-4325 3675);
FORCEPROP 1 LAST VALUE 22UF
J 0
(-4325 3775);
DISPLAY 0.489362 (-4325 3775);
PAINT SKYBLUE (-4325 3775);
FORCEPROP 1 LAST VOLTAGE 4V
J 0
(-4325 3725);
DISPLAY 0.489362 (-4325 3725);
PAINT SKYBLUE (-4325 3725);
FORCEPROP 1 LAST PACK_TYPE C0402
J 0
(-4325 3525);
DISPLAY 0.489362 (-4325 3525);
PAINT SKYBLUE (-4325 3525);
FORCEPROP 2 LAST CDS_LIB pure_quanta
J 0
(-4375 3725);
PAINT MONO (-4375 3725);
DISPLAY INVISIBLE (-4375 3725);
FORCEPROP 1 LAST PATH I58
J 0
(-4325 3875);
DISPLAY 0.978723 (-4325 3875);
PAINT WHITE (-4325 3875);
DISPLAY INVISIBLE (-4325 3875);
FORCEPROP 1 LAST PART_NUMBER CH622KMEB02
J 0
(-4325 3575);
DISPLAY 0.489362 (-4325 3575);
PAINT SKYBLUE (-4325 3575);
DISPLAY INVISIBLE (-4325 3575);
FORCEADD Q_CAP..1
(-8050 4500);
FORCEPROP 1 LAST LOCATION C2312
J 0
(-8000 4600);
DISPLAY 0.489362 (-8000 4600);
PAINT SKYBLUE (-8000 4600);
FORCEPROP 2 LAST $SEC 1
J 0
(-8000 4700);
DISPLAY 0.680851 (-8000 4700);
PAINT MONO (-8000 4700);
DISPLAY INVISIBLE (-8000 4700);
FORCEPROP 2 LAST CDS_SEC 1
J 0
(-8000 4700);
DISPLAY 1.021277 (-8000 4700);
DISPLAY INVISIBLE (-8000 4700);
FORCEPROP 1 LASTPIN (-8050 4600) $PN 1
J 0
(-8040 4580);
DISPLAY 0.489362 (-8040 4580);
FORCEPROP 1 LASTPIN (-8050 4400) $PN 2
J 0
(-8040 4380);
DISPLAY 0.489362 (-8040 4380);
FORCEPROP 1 LAST MATERIAL X6S
J 0
(-8000 4400);
DISPLAY 0.489362 (-8000 4400);
PAINT SKYBLUE (-8000 4400);
FORCEPROP 1 LAST TOLERANCE 20%
J 0
(-8000 4450);
DISPLAY 0.489362 (-8000 4450);
PAINT SKYBLUE (-8000 4450);
FORCEPROP 1 LAST VALUE 22UF
J 0
(-8000 4550);
DISPLAY 0.489362 (-8000 4550);
PAINT SKYBLUE (-8000 4550);
FORCEPROP 1 LAST VOLTAGE 4V
J 0
(-8000 4500);
DISPLAY 0.489362 (-8000 4500);
PAINT SKYBLUE (-8000 4500);
FORCEPROP 1 LAST PACK_TYPE C0402
J 0
(-8000 4300);
DISPLAY 0.489362 (-8000 4300);
PAINT SKYBLUE (-8000 4300);
FORCEPROP 2 LAST CDS_LIB pure_quanta
J 0
(-8050 4500);
PAINT MONO (-8050 4500);
DISPLAY INVISIBLE (-8050 4500);
FORCEPROP 1 LAST PATH I59
J 0
(-8000 4650);
DISPLAY 0.978723 (-8000 4650);
PAINT WHITE (-8000 4650);
DISPLAY INVISIBLE (-8000 4650);
FORCEPROP 1 LAST PART_NUMBER CH622KMEB02
J 0
(-8000 4350);
DISPLAY 0.489362 (-8000 4350);
PAINT SKYBLUE (-8000 4350);
DISPLAY INVISIBLE (-8000 4350);
FORCEADD UNIVERSAL_POWER..1
(-9400 2400);
FORCEPROP 3 LASTPIN (-9400 2350) SIG_NAME PVDDCR_CPU0_P1\g
J 0
(-9390 2360);
DISPLAY 0.659574 (-9390 2360);
PAINT MONO (-9390 2360);
DISPLAY INVISIBLE (-9390 2360);
FORCEPROP 1 LAST HDL_POWER PVDDCR_CPU0_P1
J 1
(-9400 2450);
DISPLAY 0.489362 (-9400 2450);
PAINT GREEN (-9400 2450);
FORCEPROP 2 LAST CDS_LIB pure_quanta_power
J 0
(-9400 2400);
DISPLAY INVISIBLE (-9400 2400);
FORCEPROP 1 LAST PATH I6
J 0
(-9350 2425);
DISPLAY 0.872340 (-9350 2425);
PAINT AQUA (-9350 2425);
DISPLAY INVISIBLE (-9350 2425);
FORCEADD Q_CAP..1
(-7600 4500);
FORCEPROP 1 LAST LOCATION C2318
J 0
(-7550 4600);
DISPLAY 0.489362 (-7550 4600);
PAINT SKYBLUE (-7550 4600);
FORCEPROP 2 LAST $SEC 1
J 0
(-7550 4700);
DISPLAY 0.680851 (-7550 4700);
PAINT MONO (-7550 4700);
DISPLAY INVISIBLE (-7550 4700);
FORCEPROP 2 LAST CDS_SEC 1
J 0
(-7550 4700);
DISPLAY 1.021277 (-7550 4700);
DISPLAY INVISIBLE (-7550 4700);
FORCEPROP 1 LASTPIN (-7600 4600) $PN 1
J 0
(-7590 4580);
DISPLAY 0.489362 (-7590 4580);
FORCEPROP 1 LASTPIN (-7600 4400) $PN 2
J 0
(-7590 4380);
DISPLAY 0.489362 (-7590 4380);
FORCEPROP 1 LAST MATERIAL X6S
J 0
(-7550 4400);
DISPLAY 0.489362 (-7550 4400);
PAINT SKYBLUE (-7550 4400);
FORCEPROP 1 LAST TOLERANCE 20%
J 0
(-7550 4450);
DISPLAY 0.489362 (-7550 4450);
PAINT SKYBLUE (-7550 4450);
FORCEPROP 1 LAST VALUE 22UF
J 0
(-7550 4550);
DISPLAY 0.489362 (-7550 4550);
PAINT SKYBLUE (-7550 4550);
FORCEPROP 1 LAST VOLTAGE 4V
J 0
(-7550 4500);
DISPLAY 0.489362 (-7550 4500);
PAINT SKYBLUE (-7550 4500);
FORCEPROP 1 LAST PACK_TYPE C0402
J 0
(-7550 4300);
DISPLAY 0.489362 (-7550 4300);
PAINT SKYBLUE (-7550 4300);
FORCEPROP 2 LAST CDS_LIB pure_quanta
J 0
(-7600 4500);
PAINT MONO (-7600 4500);
DISPLAY INVISIBLE (-7600 4500);
FORCEPROP 1 LAST PATH I60
J 0
(-7550 4650);
DISPLAY 0.978723 (-7550 4650);
PAINT WHITE (-7550 4650);
DISPLAY INVISIBLE (-7550 4650);
FORCEPROP 1 LAST PART_NUMBER CH622KMEB02
J 0
(-7550 4350);
DISPLAY 0.489362 (-7550 4350);
PAINT SKYBLUE (-7550 4350);
DISPLAY INVISIBLE (-7550 4350);
FORCEADD Q_CAP..1
(-7150 4500);
FORCEPROP 1 LAST LOCATION C2324
J 0
(-7100 4600);
DISPLAY 0.489362 (-7100 4600);
PAINT SKYBLUE (-7100 4600);
FORCEPROP 2 LAST $SEC 1
J 0
(-7100 4700);
DISPLAY 0.680851 (-7100 4700);
PAINT MONO (-7100 4700);
DISPLAY INVISIBLE (-7100 4700);
FORCEPROP 2 LAST CDS_SEC 1
J 0
(-7100 4700);
DISPLAY 1.021277 (-7100 4700);
DISPLAY INVISIBLE (-7100 4700);
FORCEPROP 1 LASTPIN (-7150 4600) $PN 1
J 0
(-7140 4580);
DISPLAY 0.489362 (-7140 4580);
FORCEPROP 1 LASTPIN (-7150 4400) $PN 2
J 0
(-7140 4380);
DISPLAY 0.489362 (-7140 4380);
FORCEPROP 1 LAST MATERIAL X6S
J 0
(-7100 4400);
DISPLAY 0.489362 (-7100 4400);
PAINT SKYBLUE (-7100 4400);
FORCEPROP 1 LAST TOLERANCE 20%
J 0
(-7100 4450);
DISPLAY 0.489362 (-7100 4450);
PAINT SKYBLUE (-7100 4450);
FORCEPROP 1 LAST VALUE 22UF
J 0
(-7100 4550);
DISPLAY 0.489362 (-7100 4550);
PAINT SKYBLUE (-7100 4550);
FORCEPROP 1 LAST VOLTAGE 4V
J 0
(-7100 4500);
DISPLAY 0.489362 (-7100 4500);
PAINT SKYBLUE (-7100 4500);
FORCEPROP 1 LAST PACK_TYPE C0402
J 0
(-7100 4300);
DISPLAY 0.489362 (-7100 4300);
PAINT SKYBLUE (-7100 4300);
FORCEPROP 2 LAST CDS_LIB pure_quanta
J 0
(-7150 4500);
PAINT MONO (-7150 4500);
DISPLAY INVISIBLE (-7150 4500);
FORCEPROP 1 LAST PATH I61
J 0
(-7100 4650);
DISPLAY 0.978723 (-7100 4650);
PAINT WHITE (-7100 4650);
DISPLAY INVISIBLE (-7100 4650);
FORCEPROP 1 LAST PART_NUMBER CH622KMEB02
J 0
(-7100 4350);
DISPLAY 0.489362 (-7100 4350);
PAINT SKYBLUE (-7100 4350);
DISPLAY INVISIBLE (-7100 4350);
FORCEADD Q_CAP..1
(-6700 4500);
FORCEPROP 1 LAST LOCATION C2330
J 0
(-6650 4600);
DISPLAY 0.489362 (-6650 4600);
PAINT SKYBLUE (-6650 4600);
FORCEPROP 2 LAST $SEC 1
J 0
(-6650 4700);
DISPLAY 0.680851 (-6650 4700);
PAINT MONO (-6650 4700);
DISPLAY INVISIBLE (-6650 4700);
FORCEPROP 2 LAST CDS_SEC 1
J 0
(-6650 4700);
DISPLAY 1.021277 (-6650 4700);
DISPLAY INVISIBLE (-6650 4700);
FORCEPROP 1 LASTPIN (-6700 4600) $PN 1
J 0
(-6690 4580);
DISPLAY 0.489362 (-6690 4580);
FORCEPROP 1 LASTPIN (-6700 4400) $PN 2
J 0
(-6690 4380);
DISPLAY 0.489362 (-6690 4380);
FORCEPROP 1 LAST MATERIAL X6S
J 0
(-6650 4400);
DISPLAY 0.489362 (-6650 4400);
PAINT SKYBLUE (-6650 4400);
FORCEPROP 1 LAST TOLERANCE 20%
J 0
(-6650 4450);
DISPLAY 0.489362 (-6650 4450);
PAINT SKYBLUE (-6650 4450);
FORCEPROP 1 LAST VALUE 22UF
J 0
(-6650 4550);
DISPLAY 0.489362 (-6650 4550);
PAINT SKYBLUE (-6650 4550);
FORCEPROP 1 LAST VOLTAGE 4V
J 0
(-6650 4500);
DISPLAY 0.489362 (-6650 4500);
PAINT SKYBLUE (-6650 4500);
FORCEPROP 1 LAST PACK_TYPE C0402
J 0
(-6650 4300);
DISPLAY 0.489362 (-6650 4300);
PAINT SKYBLUE (-6650 4300);
FORCEPROP 2 LAST CDS_LIB pure_quanta
J 0
(-6700 4500);
PAINT MONO (-6700 4500);
DISPLAY INVISIBLE (-6700 4500);
FORCEPROP 1 LAST PATH I62
J 0
(-6650 4650);
DISPLAY 0.978723 (-6650 4650);
PAINT WHITE (-6650 4650);
DISPLAY INVISIBLE (-6650 4650);
FORCEPROP 1 LAST PART_NUMBER CH622KMEB02
J 0
(-6650 4350);
DISPLAY 0.489362 (-6650 4350);
PAINT SKYBLUE (-6650 4350);
DISPLAY INVISIBLE (-6650 4350);
FORCEADD Q_CAP..1
(-6250 4500);
FORCEPROP 1 LAST LOCATION C2335
J 0
(-6200 4600);
DISPLAY 0.489362 (-6200 4600);
PAINT SKYBLUE (-6200 4600);
FORCEPROP 2 LAST $SEC 1
J 0
(-6200 4700);
DISPLAY 0.680851 (-6200 4700);
PAINT MONO (-6200 4700);
DISPLAY INVISIBLE (-6200 4700);
FORCEPROP 2 LAST CDS_SEC 1
J 0
(-6200 4700);
DISPLAY 1.021277 (-6200 4700);
DISPLAY INVISIBLE (-6200 4700);
FORCEPROP 1 LASTPIN (-6250 4600) $PN 1
J 0
(-6240 4580);
DISPLAY 0.489362 (-6240 4580);
FORCEPROP 1 LASTPIN (-6250 4400) $PN 2
J 0
(-6240 4380);
DISPLAY 0.489362 (-6240 4380);
FORCEPROP 1 LAST MATERIAL X6S
J 0
(-6200 4400);
DISPLAY 0.489362 (-6200 4400);
PAINT SKYBLUE (-6200 4400);
FORCEPROP 1 LAST TOLERANCE 20%
J 0
(-6200 4450);
DISPLAY 0.489362 (-6200 4450);
PAINT SKYBLUE (-6200 4450);
FORCEPROP 1 LAST VALUE 22UF
J 0
(-6200 4550);
DISPLAY 0.489362 (-6200 4550);
PAINT SKYBLUE (-6200 4550);
FORCEPROP 1 LAST VOLTAGE 4V
J 0
(-6200 4500);
DISPLAY 0.489362 (-6200 4500);
PAINT SKYBLUE (-6200 4500);
FORCEPROP 1 LAST PACK_TYPE C0402
J 0
(-6200 4300);
DISPLAY 0.489362 (-6200 4300);
PAINT SKYBLUE (-6200 4300);
FORCEPROP 2 LAST CDS_LIB pure_quanta
J 0
(-6250 4500);
PAINT MONO (-6250 4500);
DISPLAY INVISIBLE (-6250 4500);
FORCEPROP 1 LAST PATH I63
J 0
(-6200 4650);
DISPLAY 0.978723 (-6200 4650);
PAINT WHITE (-6200 4650);
DISPLAY INVISIBLE (-6200 4650);
FORCEPROP 1 LAST PART_NUMBER CH622KMEB02
J 0
(-6200 4350);
DISPLAY 0.489362 (-6200 4350);
PAINT SKYBLUE (-6200 4350);
DISPLAY INVISIBLE (-6200 4350);
FORCEADD Q_CAP..1
(-5800 4500);
FORCEPROP 1 LAST LOCATION C2340
J 0
(-5750 4600);
DISPLAY 0.489362 (-5750 4600);
PAINT SKYBLUE (-5750 4600);
FORCEPROP 2 LAST $SEC 1
J 0
(-5750 4700);
DISPLAY 0.680851 (-5750 4700);
PAINT MONO (-5750 4700);
DISPLAY INVISIBLE (-5750 4700);
FORCEPROP 2 LAST CDS_SEC 1
J 0
(-5750 4700);
DISPLAY 1.021277 (-5750 4700);
DISPLAY INVISIBLE (-5750 4700);
FORCEPROP 1 LASTPIN (-5800 4600) $PN 1
J 0
(-5790 4580);
DISPLAY 0.489362 (-5790 4580);
FORCEPROP 1 LASTPIN (-5800 4400) $PN 2
J 0
(-5790 4380);
DISPLAY 0.489362 (-5790 4380);
FORCEPROP 1 LAST MATERIAL X6S
J 0
(-5750 4400);
DISPLAY 0.489362 (-5750 4400);
PAINT SKYBLUE (-5750 4400);
FORCEPROP 1 LAST TOLERANCE 20%
J 0
(-5750 4450);
DISPLAY 0.489362 (-5750 4450);
PAINT SKYBLUE (-5750 4450);
FORCEPROP 1 LAST VALUE 22UF
J 0
(-5750 4550);
DISPLAY 0.489362 (-5750 4550);
PAINT SKYBLUE (-5750 4550);
FORCEPROP 1 LAST VOLTAGE 4V
J 0
(-5750 4500);
DISPLAY 0.489362 (-5750 4500);
PAINT SKYBLUE (-5750 4500);
FORCEPROP 1 LAST PACK_TYPE C0402
J 0
(-5750 4300);
DISPLAY 0.489362 (-5750 4300);
PAINT SKYBLUE (-5750 4300);
FORCEPROP 2 LAST CDS_LIB pure_quanta
J 0
(-5800 4500);
PAINT MONO (-5800 4500);
DISPLAY INVISIBLE (-5800 4500);
FORCEPROP 1 LAST PATH I64
J 0
(-5750 4650);
DISPLAY 0.978723 (-5750 4650);
PAINT WHITE (-5750 4650);
DISPLAY INVISIBLE (-5750 4650);
FORCEPROP 1 LAST PART_NUMBER CH622KMEB02
J 0
(-5750 4350);
DISPLAY 0.489362 (-5750 4350);
PAINT SKYBLUE (-5750 4350);
DISPLAY INVISIBLE (-5750 4350);
FORCEADD UNIVERSAL_GND..1
(-5400 4125);
FORCEPROP 3 LASTPIN (-5400 4175) SIG_NAME GND\g
J 0
(-5390 4185);
DISPLAY 0.659574 (-5390 4185);
PAINT MONO (-5390 4185);
DISPLAY INVISIBLE (-5390 4185);
FORCEPROP 2 LAST CDS_LIB pure_quanta_power
J 0
(-5400 4125);
PAINT MONO (-5400 4125);
DISPLAY INVISIBLE (-5400 4125);
FORCEPROP 1 LAST HDL_POWER GND
J 1
(-5375 4050);
DISPLAY 0.872340 (-5375 4050);
PAINT GREEN (-5375 4050);
DISPLAY INVISIBLE (-5375 4050);
FORCEPROP 1 LAST PATH I65
J 0
(-5325 4125);
DISPLAY 0.872340 (-5325 4125);
PAINT AQUA (-5325 4125);
DISPLAY INVISIBLE (-5325 4125);
FORCEADD Q_CAP..1
(-5400 4500);
FORCEPROP 1 LAST LOCATION C2345
J 0
(-5350 4600);
DISPLAY 0.489362 (-5350 4600);
PAINT SKYBLUE (-5350 4600);
FORCEPROP 2 LAST $SEC 1
J 0
(-5350 4700);
DISPLAY 0.680851 (-5350 4700);
PAINT MONO (-5350 4700);
DISPLAY INVISIBLE (-5350 4700);
FORCEPROP 2 LAST CDS_SEC 1
J 0
(-5350 4700);
DISPLAY 1.021277 (-5350 4700);
DISPLAY INVISIBLE (-5350 4700);
FORCEPROP 1 LASTPIN (-5400 4600) $PN 1
J 0
(-5390 4580);
DISPLAY 0.489362 (-5390 4580);
FORCEPROP 1 LASTPIN (-5400 4400) $PN 2
J 0
(-5390 4380);
DISPLAY 0.489362 (-5390 4380);
FORCEPROP 1 LAST MATERIAL X6S
J 0
(-5350 4400);
DISPLAY 0.489362 (-5350 4400);
PAINT SKYBLUE (-5350 4400);
FORCEPROP 1 LAST TOLERANCE 20%
J 0
(-5350 4450);
DISPLAY 0.489362 (-5350 4450);
PAINT SKYBLUE (-5350 4450);
FORCEPROP 1 LAST VALUE 22UF
J 0
(-5350 4550);
DISPLAY 0.489362 (-5350 4550);
PAINT SKYBLUE (-5350 4550);
FORCEPROP 1 LAST VOLTAGE 4V
J 0
(-5350 4500);
DISPLAY 0.489362 (-5350 4500);
PAINT SKYBLUE (-5350 4500);
FORCEPROP 1 LAST PACK_TYPE C0402
J 0
(-5350 4300);
DISPLAY 0.489362 (-5350 4300);
PAINT SKYBLUE (-5350 4300);
FORCEPROP 2 LAST CDS_LIB pure_quanta
J 0
(-5400 4500);
PAINT MONO (-5400 4500);
DISPLAY INVISIBLE (-5400 4500);
FORCEPROP 1 LAST PATH I66
J 0
(-5350 4650);
DISPLAY 0.978723 (-5350 4650);
PAINT WHITE (-5350 4650);
DISPLAY INVISIBLE (-5350 4650);
FORCEPROP 1 LAST PART_NUMBER CH622KMEB02
J 0
(-5350 4350);
DISPLAY 0.489362 (-5350 4350);
PAINT SKYBLUE (-5350 4350);
DISPLAY INVISIBLE (-5350 4350);
FORCEADD UNIVERSAL_POWER..1
(-4825 4000);
FORCEPROP 3 LASTPIN (-4825 3950) SIG_NAME PVDDCR_CPU1_P1\g
J 0
(-4815 3960);
DISPLAY 0.659574 (-4815 3960);
PAINT MONO (-4815 3960);
DISPLAY INVISIBLE (-4815 3960);
FORCEPROP 1 LAST HDL_POWER PVDDCR_CPU1_P1
J 1
(-4825 4050);
DISPLAY 0.489362 (-4825 4050);
PAINT GREEN (-4825 4050);
FORCEPROP 2 LAST CDS_LIB pure_quanta_power
J 0
(-4825 4000);
DISPLAY INVISIBLE (-4825 4000);
FORCEPROP 1 LAST PATH I67
J 0
(-4775 4025);
DISPLAY 0.872340 (-4775 4025);
PAINT AQUA (-4775 4025);
DISPLAY INVISIBLE (-4775 4025);
FORCEADD Q_CAP..1
(-4375 4500);
FORCEPROP 1 LAST LOCATION C2356
J 0
(-4325 4600);
DISPLAY 0.489362 (-4325 4600);
PAINT SKYBLUE (-4325 4600);
FORCEPROP 2 LAST $SEC 1
J 0
(-4325 4700);
DISPLAY 0.680851 (-4325 4700);
PAINT MONO (-4325 4700);
DISPLAY INVISIBLE (-4325 4700);
FORCEPROP 2 LAST CDS_SEC 1
J 0
(-4325 4700);
DISPLAY 1.021277 (-4325 4700);
DISPLAY INVISIBLE (-4325 4700);
FORCEPROP 1 LASTPIN (-4375 4600) $PN 1
J 0
(-4365 4580);
DISPLAY 0.489362 (-4365 4580);
FORCEPROP 1 LASTPIN (-4375 4400) $PN 2
J 0
(-4365 4380);
DISPLAY 0.489362 (-4365 4380);
FORCEPROP 1 LAST MATERIAL X6S
J 0
(-4325 4400);
DISPLAY 0.489362 (-4325 4400);
PAINT SKYBLUE (-4325 4400);
FORCEPROP 1 LAST TOLERANCE 20%
J 0
(-4325 4450);
DISPLAY 0.489362 (-4325 4450);
PAINT SKYBLUE (-4325 4450);
FORCEPROP 1 LAST VALUE 22UF
J 0
(-4325 4550);
DISPLAY 0.489362 (-4325 4550);
PAINT SKYBLUE (-4325 4550);
FORCEPROP 1 LAST VOLTAGE 4V
J 0
(-4325 4500);
DISPLAY 0.489362 (-4325 4500);
PAINT SKYBLUE (-4325 4500);
FORCEPROP 1 LAST PACK_TYPE C0402
J 0
(-4325 4300);
DISPLAY 0.489362 (-4325 4300);
PAINT SKYBLUE (-4325 4300);
FORCEPROP 2 LAST CDS_LIB pure_quanta
J 0
(-4375 4500);
PAINT MONO (-4375 4500);
DISPLAY INVISIBLE (-4375 4500);
FORCEPROP 1 LAST PATH I68
J 0
(-4325 4650);
DISPLAY 0.978723 (-4325 4650);
PAINT WHITE (-4325 4650);
DISPLAY INVISIBLE (-4325 4650);
FORCEPROP 1 LAST PART_NUMBER CH622KMEB02
J 0
(-4325 4350);
DISPLAY 0.489362 (-4325 4350);
PAINT SKYBLUE (-4325 4350);
DISPLAY INVISIBLE (-4325 4350);
FORCEADD UNIVERSAL_POWER..1
(-4825 4775);
FORCEPROP 3 LASTPIN (-4825 4725) SIG_NAME PVDDCR_CPU1_P1\g
J 0
(-4815 4735);
DISPLAY 0.659574 (-4815 4735);
PAINT MONO (-4815 4735);
DISPLAY INVISIBLE (-4815 4735);
FORCEPROP 1 LAST HDL_POWER PVDDCR_CPU1_P1
J 1
(-4825 4825);
DISPLAY 0.489362 (-4825 4825);
PAINT GREEN (-4825 4825);
FORCEPROP 2 LAST CDS_LIB pure_quanta_power
J 0
(-4825 4775);
DISPLAY INVISIBLE (-4825 4775);
FORCEPROP 1 LAST PATH I69
J 0
(-4775 4800);
DISPLAY 0.872340 (-4775 4800);
PAINT AQUA (-4775 4800);
DISPLAY INVISIBLE (-4775 4800);
FORCEADD Q_CAP..1
(-9400 2925);
FORCEPROP 1 LAST LOCATION C2296
J 0
(-9350 3025);
DISPLAY 0.489362 (-9350 3025);
PAINT SKYBLUE (-9350 3025);
FORCEPROP 2 LAST $SEC 1
J 0
(-9350 3125);
DISPLAY 0.680851 (-9350 3125);
PAINT MONO (-9350 3125);
DISPLAY INVISIBLE (-9350 3125);
FORCEPROP 2 LAST CDS_SEC 1
J 0
(-9350 3125);
DISPLAY 1.021277 (-9350 3125);
DISPLAY INVISIBLE (-9350 3125);
FORCEPROP 1 LASTPIN (-9400 3025) $PN 1
J 0
(-9390 3005);
DISPLAY 0.489362 (-9390 3005);
FORCEPROP 1 LASTPIN (-9400 2825) $PN 2
J 0
(-9390 2805);
DISPLAY 0.489362 (-9390 2805);
FORCEPROP 1 LAST MATERIAL X6S
J 0
(-9350 2825);
DISPLAY 0.489362 (-9350 2825);
PAINT SKYBLUE (-9350 2825);
FORCEPROP 1 LAST TOLERANCE 20%
J 0
(-9350 2875);
DISPLAY 0.489362 (-9350 2875);
PAINT SKYBLUE (-9350 2875);
FORCEPROP 1 LAST VALUE 22UF
J 0
(-9350 2975);
DISPLAY 0.489362 (-9350 2975);
PAINT SKYBLUE (-9350 2975);
FORCEPROP 1 LAST VOLTAGE 4V
J 0
(-9350 2925);
DISPLAY 0.489362 (-9350 2925);
PAINT SKYBLUE (-9350 2925);
FORCEPROP 1 LAST PACK_TYPE C0402
J 0
(-9350 2725);
DISPLAY 0.489362 (-9350 2725);
PAINT SKYBLUE (-9350 2725);
FORCEPROP 2 LAST CDS_LIB pure_quanta
J 0
(-9400 2925);
PAINT MONO (-9400 2925);
DISPLAY INVISIBLE (-9400 2925);
FORCEPROP 1 LAST PATH I7
J 0
(-9350 3075);
DISPLAY 0.978723 (-9350 3075);
PAINT WHITE (-9350 3075);
DISPLAY INVISIBLE (-9350 3075);
FORCEPROP 1 LAST PART_NUMBER CH622KMEB02
J 0
(-9350 2775);
DISPLAY 0.489362 (-9350 2775);
PAINT SKYBLUE (-9350 2775);
DISPLAY INVISIBLE (-9350 2775);
FORCEADD Q_CAP..1
(-3925 1325);
FORCEPROP 1 LAST LOCATION C2366
J 0
(-3875 1425);
DISPLAY 0.489362 (-3875 1425);
PAINT SKYBLUE (-3875 1425);
FORCEPROP 2 LAST $SEC 1
J 0
(-3875 1525);
DISPLAY 0.680851 (-3875 1525);
PAINT MONO (-3875 1525);
DISPLAY INVISIBLE (-3875 1525);
FORCEPROP 2 LAST CDS_SEC 1
J 0
(-3875 1525);
DISPLAY 1.021277 (-3875 1525);
DISPLAY INVISIBLE (-3875 1525);
FORCEPROP 1 LASTPIN (-3925 1425) $PN 1
J 0
(-3915 1405);
DISPLAY 0.489362 (-3915 1405);
FORCEPROP 1 LASTPIN (-3925 1225) $PN 2
J 0
(-3915 1205);
DISPLAY 0.489362 (-3915 1205);
FORCEPROP 1 LAST MATERIAL X6S
J 0
(-3875 1225);
DISPLAY 0.489362 (-3875 1225);
PAINT SKYBLUE (-3875 1225);
FORCEPROP 1 LAST TOLERANCE 20%
J 0
(-3875 1275);
DISPLAY 0.489362 (-3875 1275);
PAINT SKYBLUE (-3875 1275);
FORCEPROP 1 LAST VALUE 22UF
J 0
(-3875 1375);
DISPLAY 0.489362 (-3875 1375);
PAINT SKYBLUE (-3875 1375);
FORCEPROP 1 LAST VOLTAGE 4V
J 0
(-3875 1325);
DISPLAY 0.489362 (-3875 1325);
PAINT SKYBLUE (-3875 1325);
FORCEPROP 1 LAST PACK_TYPE C0402
J 0
(-3875 1125);
DISPLAY 0.489362 (-3875 1125);
PAINT SKYBLUE (-3875 1125);
FORCEPROP 2 LAST CDS_LIB pure_quanta
J 0
(-3925 1325);
PAINT MONO (-3925 1325);
DISPLAY INVISIBLE (-3925 1325);
FORCEPROP 1 LAST PATH I70
J 0
(-3875 1475);
DISPLAY 0.978723 (-3875 1475);
PAINT WHITE (-3875 1475);
DISPLAY INVISIBLE (-3875 1475);
FORCEPROP 1 LAST PART_NUMBER CH622KMEB02
J 0
(-3875 1175);
DISPLAY 0.489362 (-3875 1175);
PAINT SKYBLUE (-3875 1175);
DISPLAY INVISIBLE (-3875 1175);
FORCEADD Q_CAP..1
(-3475 1325);
FORCEPROP 1 LAST LOCATION C2372
J 0
(-3425 1425);
DISPLAY 0.489362 (-3425 1425);
PAINT SKYBLUE (-3425 1425);
FORCEPROP 2 LAST $SEC 1
J 0
(-3425 1525);
DISPLAY 0.680851 (-3425 1525);
PAINT MONO (-3425 1525);
DISPLAY INVISIBLE (-3425 1525);
FORCEPROP 2 LAST CDS_SEC 1
J 0
(-3425 1525);
DISPLAY 1.021277 (-3425 1525);
DISPLAY INVISIBLE (-3425 1525);
FORCEPROP 1 LASTPIN (-3475 1425) $PN 1
J 0
(-3465 1405);
DISPLAY 0.489362 (-3465 1405);
FORCEPROP 1 LASTPIN (-3475 1225) $PN 2
J 0
(-3465 1205);
DISPLAY 0.489362 (-3465 1205);
FORCEPROP 1 LAST MATERIAL X6S
J 0
(-3425 1225);
DISPLAY 0.489362 (-3425 1225);
PAINT SKYBLUE (-3425 1225);
FORCEPROP 1 LAST TOLERANCE 20%
J 0
(-3425 1275);
DISPLAY 0.489362 (-3425 1275);
PAINT SKYBLUE (-3425 1275);
FORCEPROP 1 LAST VALUE 22UF
J 0
(-3425 1375);
DISPLAY 0.489362 (-3425 1375);
PAINT SKYBLUE (-3425 1375);
FORCEPROP 1 LAST VOLTAGE 4V
J 0
(-3425 1325);
DISPLAY 0.489362 (-3425 1325);
PAINT SKYBLUE (-3425 1325);
FORCEPROP 1 LAST PACK_TYPE C0402
J 0
(-3425 1125);
DISPLAY 0.489362 (-3425 1125);
PAINT SKYBLUE (-3425 1125);
FORCEPROP 2 LAST CDS_LIB pure_quanta
J 0
(-3475 1325);
PAINT MONO (-3475 1325);
DISPLAY INVISIBLE (-3475 1325);
FORCEPROP 1 LAST PATH I71
J 0
(-3425 1475);
DISPLAY 0.978723 (-3425 1475);
PAINT WHITE (-3425 1475);
DISPLAY INVISIBLE (-3425 1475);
FORCEPROP 1 LAST PART_NUMBER CH622KMEB02
J 0
(-3425 1175);
DISPLAY 0.489362 (-3425 1175);
PAINT SKYBLUE (-3425 1175);
DISPLAY INVISIBLE (-3425 1175);
FORCEADD Q_CAP..1
(-3025 1325);
FORCEPROP 1 LAST LOCATION C2378
J 0
(-2975 1425);
DISPLAY 0.489362 (-2975 1425);
PAINT SKYBLUE (-2975 1425);
FORCEPROP 2 LAST $SEC 1
J 0
(-2975 1525);
DISPLAY 0.680851 (-2975 1525);
PAINT MONO (-2975 1525);
DISPLAY INVISIBLE (-2975 1525);
FORCEPROP 2 LAST CDS_SEC 1
J 0
(-2975 1525);
DISPLAY 1.021277 (-2975 1525);
DISPLAY INVISIBLE (-2975 1525);
FORCEPROP 1 LASTPIN (-3025 1425) $PN 1
J 0
(-3015 1405);
DISPLAY 0.489362 (-3015 1405);
FORCEPROP 1 LASTPIN (-3025 1225) $PN 2
J 0
(-3015 1205);
DISPLAY 0.489362 (-3015 1205);
FORCEPROP 1 LAST MATERIAL X6S
J 0
(-2975 1225);
DISPLAY 0.489362 (-2975 1225);
PAINT SKYBLUE (-2975 1225);
FORCEPROP 1 LAST TOLERANCE 20%
J 0
(-2975 1275);
DISPLAY 0.489362 (-2975 1275);
PAINT SKYBLUE (-2975 1275);
FORCEPROP 1 LAST VALUE 22UF
J 0
(-2975 1375);
DISPLAY 0.489362 (-2975 1375);
PAINT SKYBLUE (-2975 1375);
FORCEPROP 1 LAST VOLTAGE 4V
J 0
(-2975 1325);
DISPLAY 0.489362 (-2975 1325);
PAINT SKYBLUE (-2975 1325);
FORCEPROP 1 LAST PACK_TYPE C0402
J 0
(-2975 1125);
DISPLAY 0.489362 (-2975 1125);
PAINT SKYBLUE (-2975 1125);
FORCEPROP 2 LAST CDS_LIB pure_quanta
J 0
(-3025 1325);
PAINT MONO (-3025 1325);
DISPLAY INVISIBLE (-3025 1325);
FORCEPROP 1 LAST PATH I72
J 0
(-2975 1475);
DISPLAY 0.978723 (-2975 1475);
PAINT WHITE (-2975 1475);
DISPLAY INVISIBLE (-2975 1475);
FORCEPROP 1 LAST PART_NUMBER CH622KMEB02
J 0
(-2975 1175);
DISPLAY 0.489362 (-2975 1175);
PAINT SKYBLUE (-2975 1175);
DISPLAY INVISIBLE (-2975 1175);
FORCEADD UNIVERSAL_GND..1
(-3025 950);
FORCEPROP 3 LASTPIN (-3025 1000) SIG_NAME GND\g
J 0
(-3015 1010);
DISPLAY 0.659574 (-3015 1010);
PAINT MONO (-3015 1010);
DISPLAY INVISIBLE (-3015 1010);
FORCEPROP 2 LAST CDS_LIB pure_quanta_power
J 0
(-3025 950);
DISPLAY INVISIBLE (-3025 950);
FORCEPROP 1 LAST HDL_POWER GND
J 1
(-3000 875);
DISPLAY 0.872340 (-3000 875);
PAINT GREEN (-3000 875);
DISPLAY INVISIBLE (-3000 875);
FORCEPROP 1 LAST PATH I73
J 0
(-2950 950);
DISPLAY 0.872340 (-2950 950);
PAINT AQUA (-2950 950);
DISPLAY INVISIBLE (-2950 950);
FORCEADD Q_CAP..1
(-3925 2125);
FORCEPROP 1 LAST LOCATION C2365
J 0
(-3875 2225);
DISPLAY 0.489362 (-3875 2225);
PAINT SKYBLUE (-3875 2225);
FORCEPROP 2 LAST $SEC 1
J 0
(-3875 2325);
DISPLAY 0.680851 (-3875 2325);
PAINT MONO (-3875 2325);
DISPLAY INVISIBLE (-3875 2325);
FORCEPROP 2 LAST CDS_SEC 1
J 0
(-3875 2325);
DISPLAY 1.021277 (-3875 2325);
DISPLAY INVISIBLE (-3875 2325);
FORCEPROP 1 LASTPIN (-3925 2225) $PN 1
J 0
(-3915 2205);
DISPLAY 0.489362 (-3915 2205);
FORCEPROP 1 LASTPIN (-3925 2025) $PN 2
J 0
(-3915 2005);
DISPLAY 0.489362 (-3915 2005);
FORCEPROP 1 LAST MATERIAL X6S
J 0
(-3875 2025);
DISPLAY 0.489362 (-3875 2025);
PAINT SKYBLUE (-3875 2025);
FORCEPROP 1 LAST TOLERANCE 20%
J 0
(-3875 2075);
DISPLAY 0.489362 (-3875 2075);
PAINT SKYBLUE (-3875 2075);
FORCEPROP 1 LAST VALUE 22UF
J 0
(-3875 2175);
DISPLAY 0.489362 (-3875 2175);
PAINT SKYBLUE (-3875 2175);
FORCEPROP 1 LAST VOLTAGE 4V
J 0
(-3875 2125);
DISPLAY 0.489362 (-3875 2125);
PAINT SKYBLUE (-3875 2125);
FORCEPROP 1 LAST PACK_TYPE C0402
J 0
(-3875 1925);
DISPLAY 0.489362 (-3875 1925);
PAINT SKYBLUE (-3875 1925);
FORCEPROP 2 LAST CDS_LIB pure_quanta
J 0
(-3925 2125);
PAINT MONO (-3925 2125);
DISPLAY INVISIBLE (-3925 2125);
FORCEPROP 1 LAST PATH I74
J 0
(-3875 2275);
DISPLAY 0.978723 (-3875 2275);
PAINT WHITE (-3875 2275);
DISPLAY INVISIBLE (-3875 2275);
FORCEPROP 1 LAST PART_NUMBER CH622KMEB02
J 0
(-3875 1975);
DISPLAY 0.489362 (-3875 1975);
PAINT SKYBLUE (-3875 1975);
DISPLAY INVISIBLE (-3875 1975);
FORCEADD Q_CAP..1
(-3475 2125);
FORCEPROP 1 LAST LOCATION C2371
J 0
(-3425 2225);
DISPLAY 0.489362 (-3425 2225);
PAINT SKYBLUE (-3425 2225);
FORCEPROP 2 LAST $SEC 1
J 0
(-3425 2325);
DISPLAY 0.680851 (-3425 2325);
PAINT MONO (-3425 2325);
DISPLAY INVISIBLE (-3425 2325);
FORCEPROP 2 LAST CDS_SEC 1
J 0
(-3425 2325);
DISPLAY 1.021277 (-3425 2325);
DISPLAY INVISIBLE (-3425 2325);
FORCEPROP 1 LASTPIN (-3475 2225) $PN 1
J 0
(-3465 2205);
DISPLAY 0.489362 (-3465 2205);
FORCEPROP 1 LASTPIN (-3475 2025) $PN 2
J 0
(-3465 2005);
DISPLAY 0.489362 (-3465 2005);
FORCEPROP 1 LAST MATERIAL X6S
J 0
(-3425 2025);
DISPLAY 0.489362 (-3425 2025);
PAINT SKYBLUE (-3425 2025);
FORCEPROP 1 LAST TOLERANCE 20%
J 0
(-3425 2075);
DISPLAY 0.489362 (-3425 2075);
PAINT SKYBLUE (-3425 2075);
FORCEPROP 1 LAST VALUE 22UF
J 0
(-3425 2175);
DISPLAY 0.489362 (-3425 2175);
PAINT SKYBLUE (-3425 2175);
FORCEPROP 1 LAST VOLTAGE 4V
J 0
(-3425 2125);
DISPLAY 0.489362 (-3425 2125);
PAINT SKYBLUE (-3425 2125);
FORCEPROP 1 LAST PACK_TYPE C0402
J 0
(-3425 1925);
DISPLAY 0.489362 (-3425 1925);
PAINT SKYBLUE (-3425 1925);
FORCEPROP 2 LAST CDS_LIB pure_quanta
J 0
(-3475 2125);
PAINT MONO (-3475 2125);
DISPLAY INVISIBLE (-3475 2125);
FORCEPROP 1 LAST PATH I75
J 0
(-3425 2275);
DISPLAY 0.978723 (-3425 2275);
PAINT WHITE (-3425 2275);
DISPLAY INVISIBLE (-3425 2275);
FORCEPROP 1 LAST PART_NUMBER CH622KMEB02
J 0
(-3425 1975);
DISPLAY 0.489362 (-3425 1975);
PAINT SKYBLUE (-3425 1975);
DISPLAY INVISIBLE (-3425 1975);
FORCEADD Q_CAP..1
(-3925 2925);
FORCEPROP 1 LAST LOCATION C2364
J 0
(-3875 3025);
DISPLAY 0.489362 (-3875 3025);
PAINT SKYBLUE (-3875 3025);
FORCEPROP 2 LAST $SEC 1
J 0
(-3875 3125);
DISPLAY 0.680851 (-3875 3125);
PAINT MONO (-3875 3125);
DISPLAY INVISIBLE (-3875 3125);
FORCEPROP 2 LAST CDS_SEC 1
J 0
(-3875 3125);
DISPLAY 1.021277 (-3875 3125);
DISPLAY INVISIBLE (-3875 3125);
FORCEPROP 1 LASTPIN (-3925 3025) $PN 1
J 0
(-3915 3005);
DISPLAY 0.489362 (-3915 3005);
FORCEPROP 1 LASTPIN (-3925 2825) $PN 2
J 0
(-3915 2805);
DISPLAY 0.489362 (-3915 2805);
FORCEPROP 1 LAST MATERIAL X6S
J 0
(-3875 2825);
DISPLAY 0.489362 (-3875 2825);
PAINT SKYBLUE (-3875 2825);
FORCEPROP 1 LAST TOLERANCE 20%
J 0
(-3875 2875);
DISPLAY 0.489362 (-3875 2875);
PAINT SKYBLUE (-3875 2875);
FORCEPROP 1 LAST VALUE 22UF
J 0
(-3875 2975);
DISPLAY 0.489362 (-3875 2975);
PAINT SKYBLUE (-3875 2975);
FORCEPROP 1 LAST VOLTAGE 4V
J 0
(-3875 2925);
DISPLAY 0.489362 (-3875 2925);
PAINT SKYBLUE (-3875 2925);
FORCEPROP 1 LAST PACK_TYPE C0402
J 0
(-3875 2725);
DISPLAY 0.489362 (-3875 2725);
PAINT SKYBLUE (-3875 2725);
FORCEPROP 2 LAST CDS_LIB pure_quanta
J 0
(-3925 2925);
PAINT MONO (-3925 2925);
DISPLAY INVISIBLE (-3925 2925);
FORCEPROP 1 LAST PATH I76
J 0
(-3875 3075);
DISPLAY 0.978723 (-3875 3075);
PAINT WHITE (-3875 3075);
DISPLAY INVISIBLE (-3875 3075);
FORCEPROP 1 LAST PART_NUMBER CH622KMEB02
J 0
(-3875 2775);
DISPLAY 0.489362 (-3875 2775);
PAINT SKYBLUE (-3875 2775);
DISPLAY INVISIBLE (-3875 2775);
FORCEADD Q_CAP..1
(-3925 3725);
FORCEPROP 1 LAST LOCATION C2363
J 0
(-3875 3825);
DISPLAY 0.489362 (-3875 3825);
PAINT SKYBLUE (-3875 3825);
FORCEPROP 2 LAST $SEC 1
J 0
(-3875 3925);
DISPLAY 0.680851 (-3875 3925);
PAINT MONO (-3875 3925);
DISPLAY INVISIBLE (-3875 3925);
FORCEPROP 2 LAST CDS_SEC 1
J 0
(-3875 3925);
DISPLAY 1.021277 (-3875 3925);
DISPLAY INVISIBLE (-3875 3925);
FORCEPROP 1 LASTPIN (-3925 3825) $PN 1
J 0
(-3915 3805);
DISPLAY 0.489362 (-3915 3805);
FORCEPROP 1 LASTPIN (-3925 3625) $PN 2
J 0
(-3915 3605);
DISPLAY 0.489362 (-3915 3605);
FORCEPROP 1 LAST MATERIAL X6S
J 0
(-3875 3625);
DISPLAY 0.489362 (-3875 3625);
PAINT SKYBLUE (-3875 3625);
FORCEPROP 1 LAST TOLERANCE 20%
J 0
(-3875 3675);
DISPLAY 0.489362 (-3875 3675);
PAINT SKYBLUE (-3875 3675);
FORCEPROP 1 LAST VALUE 22UF
J 0
(-3875 3775);
DISPLAY 0.489362 (-3875 3775);
PAINT SKYBLUE (-3875 3775);
FORCEPROP 1 LAST VOLTAGE 4V
J 0
(-3875 3725);
DISPLAY 0.489362 (-3875 3725);
PAINT SKYBLUE (-3875 3725);
FORCEPROP 1 LAST PACK_TYPE C0402
J 0
(-3875 3525);
DISPLAY 0.489362 (-3875 3525);
PAINT SKYBLUE (-3875 3525);
FORCEPROP 2 LAST CDS_LIB pure_quanta
J 0
(-3925 3725);
PAINT MONO (-3925 3725);
DISPLAY INVISIBLE (-3925 3725);
FORCEPROP 1 LAST PATH I77
J 0
(-3875 3875);
DISPLAY 0.978723 (-3875 3875);
PAINT WHITE (-3875 3875);
DISPLAY INVISIBLE (-3875 3875);
FORCEPROP 1 LAST PART_NUMBER CH622KMEB02
J 0
(-3875 3575);
DISPLAY 0.489362 (-3875 3575);
PAINT SKYBLUE (-3875 3575);
DISPLAY INVISIBLE (-3875 3575);
FORCEADD Q_CAP..1
(-3475 2925);
FORCEPROP 1 LAST LOCATION C2370
J 0
(-3425 3025);
DISPLAY 0.489362 (-3425 3025);
PAINT SKYBLUE (-3425 3025);
FORCEPROP 2 LAST $SEC 1
J 0
(-3425 3125);
DISPLAY 0.680851 (-3425 3125);
PAINT MONO (-3425 3125);
DISPLAY INVISIBLE (-3425 3125);
FORCEPROP 2 LAST CDS_SEC 1
J 0
(-3425 3125);
DISPLAY 1.021277 (-3425 3125);
DISPLAY INVISIBLE (-3425 3125);
FORCEPROP 1 LASTPIN (-3475 3025) $PN 1
J 0
(-3465 3005);
DISPLAY 0.489362 (-3465 3005);
FORCEPROP 1 LASTPIN (-3475 2825) $PN 2
J 0
(-3465 2805);
DISPLAY 0.489362 (-3465 2805);
FORCEPROP 1 LAST MATERIAL X6S
J 0
(-3425 2825);
DISPLAY 0.489362 (-3425 2825);
PAINT SKYBLUE (-3425 2825);
FORCEPROP 1 LAST TOLERANCE 20%
J 0
(-3425 2875);
DISPLAY 0.489362 (-3425 2875);
PAINT SKYBLUE (-3425 2875);
FORCEPROP 1 LAST VALUE 22UF
J 0
(-3425 2975);
DISPLAY 0.489362 (-3425 2975);
PAINT SKYBLUE (-3425 2975);
FORCEPROP 1 LAST VOLTAGE 4V
J 0
(-3425 2925);
DISPLAY 0.489362 (-3425 2925);
PAINT SKYBLUE (-3425 2925);
FORCEPROP 1 LAST PACK_TYPE C0402
J 0
(-3425 2725);
DISPLAY 0.489362 (-3425 2725);
PAINT SKYBLUE (-3425 2725);
FORCEPROP 2 LAST CDS_LIB pure_quanta
J 0
(-3475 2925);
PAINT MONO (-3475 2925);
DISPLAY INVISIBLE (-3475 2925);
FORCEPROP 1 LAST PATH I78
J 0
(-3425 3075);
DISPLAY 0.978723 (-3425 3075);
PAINT WHITE (-3425 3075);
DISPLAY INVISIBLE (-3425 3075);
FORCEPROP 1 LAST PART_NUMBER CH622KMEB02
J 0
(-3425 2775);
DISPLAY 0.489362 (-3425 2775);
PAINT SKYBLUE (-3425 2775);
DISPLAY INVISIBLE (-3425 2775);
FORCEADD Q_CAP..1
(-3475 3725);
FORCEPROP 1 LAST LOCATION C2369
J 0
(-3425 3825);
DISPLAY 0.489362 (-3425 3825);
PAINT SKYBLUE (-3425 3825);
FORCEPROP 2 LAST $SEC 1
J 0
(-3425 3925);
DISPLAY 0.680851 (-3425 3925);
PAINT MONO (-3425 3925);
DISPLAY INVISIBLE (-3425 3925);
FORCEPROP 2 LAST CDS_SEC 1
J 0
(-3425 3925);
DISPLAY 1.021277 (-3425 3925);
DISPLAY INVISIBLE (-3425 3925);
FORCEPROP 1 LASTPIN (-3475 3825) $PN 1
J 0
(-3465 3805);
DISPLAY 0.489362 (-3465 3805);
FORCEPROP 1 LASTPIN (-3475 3625) $PN 2
J 0
(-3465 3605);
DISPLAY 0.489362 (-3465 3605);
FORCEPROP 1 LAST MATERIAL X6S
J 0
(-3425 3625);
DISPLAY 0.489362 (-3425 3625);
PAINT SKYBLUE (-3425 3625);
FORCEPROP 1 LAST TOLERANCE 20%
J 0
(-3425 3675);
DISPLAY 0.489362 (-3425 3675);
PAINT SKYBLUE (-3425 3675);
FORCEPROP 1 LAST VALUE 22UF
J 0
(-3425 3775);
DISPLAY 0.489362 (-3425 3775);
PAINT SKYBLUE (-3425 3775);
FORCEPROP 1 LAST VOLTAGE 4V
J 0
(-3425 3725);
DISPLAY 0.489362 (-3425 3725);
PAINT SKYBLUE (-3425 3725);
FORCEPROP 1 LAST PACK_TYPE C0402
J 0
(-3425 3525);
DISPLAY 0.489362 (-3425 3525);
PAINT SKYBLUE (-3425 3525);
FORCEPROP 2 LAST CDS_LIB pure_quanta
J 0
(-3475 3725);
PAINT MONO (-3475 3725);
DISPLAY INVISIBLE (-3475 3725);
FORCEPROP 1 LAST PATH I79
J 0
(-3425 3875);
DISPLAY 0.978723 (-3425 3875);
PAINT WHITE (-3425 3875);
DISPLAY INVISIBLE (-3425 3875);
FORCEPROP 1 LAST PART_NUMBER CH622KMEB02
J 0
(-3425 3575);
DISPLAY 0.489362 (-3425 3575);
PAINT SKYBLUE (-3425 3575);
DISPLAY INVISIBLE (-3425 3575);
FORCEADD UNIVERSAL_POWER..1
(-9400 3200);
FORCEPROP 3 LASTPIN (-9400 3150) SIG_NAME PVDDCR_CPU0_P1\g
J 0
(-9390 3160);
DISPLAY 0.659574 (-9390 3160);
PAINT MONO (-9390 3160);
DISPLAY INVISIBLE (-9390 3160);
FORCEPROP 1 LAST HDL_POWER PVDDCR_CPU0_P1
J 1
(-9400 3250);
DISPLAY 0.489362 (-9400 3250);
PAINT GREEN (-9400 3250);
FORCEPROP 2 LAST CDS_LIB pure_quanta_power
J 0
(-9400 3200);
DISPLAY INVISIBLE (-9400 3200);
FORCEPROP 1 LAST PATH I8
J 0
(-9350 3225);
DISPLAY 0.872340 (-9350 3225);
PAINT AQUA (-9350 3225);
DISPLAY INVISIBLE (-9350 3225);
FORCEADD Q_CAP..1
(-3025 2925);
FORCEPROP 1 LAST LOCATION C2376
J 0
(-2975 3025);
DISPLAY 0.489362 (-2975 3025);
PAINT SKYBLUE (-2975 3025);
FORCEPROP 2 LAST $SEC 1
J 0
(-2975 3125);
DISPLAY 0.680851 (-2975 3125);
PAINT MONO (-2975 3125);
DISPLAY INVISIBLE (-2975 3125);
FORCEPROP 2 LAST CDS_SEC 1
J 0
(-2975 3125);
DISPLAY 1.021277 (-2975 3125);
DISPLAY INVISIBLE (-2975 3125);
FORCEPROP 1 LASTPIN (-3025 3025) $PN 1
J 0
(-3015 3005);
DISPLAY 0.489362 (-3015 3005);
FORCEPROP 1 LASTPIN (-3025 2825) $PN 2
J 0
(-3015 2805);
DISPLAY 0.489362 (-3015 2805);
FORCEPROP 1 LAST MATERIAL X6S
J 0
(-2975 2825);
DISPLAY 0.489362 (-2975 2825);
PAINT SKYBLUE (-2975 2825);
FORCEPROP 1 LAST TOLERANCE 20%
J 0
(-2975 2875);
DISPLAY 0.489362 (-2975 2875);
PAINT SKYBLUE (-2975 2875);
FORCEPROP 1 LAST VALUE 22UF
J 0
(-2975 2975);
DISPLAY 0.489362 (-2975 2975);
PAINT SKYBLUE (-2975 2975);
FORCEPROP 1 LAST VOLTAGE 4V
J 0
(-2975 2925);
DISPLAY 0.489362 (-2975 2925);
PAINT SKYBLUE (-2975 2925);
FORCEPROP 1 LAST PACK_TYPE C0402
J 0
(-2975 2725);
DISPLAY 0.489362 (-2975 2725);
PAINT SKYBLUE (-2975 2725);
FORCEPROP 2 LAST CDS_LIB pure_quanta
J 0
(-3025 2925);
PAINT MONO (-3025 2925);
DISPLAY INVISIBLE (-3025 2925);
FORCEPROP 1 LAST PATH I80
J 0
(-2975 3075);
DISPLAY 0.978723 (-2975 3075);
PAINT WHITE (-2975 3075);
DISPLAY INVISIBLE (-2975 3075);
FORCEPROP 1 LAST PART_NUMBER CH622KMEB02
J 0
(-2975 2775);
DISPLAY 0.489362 (-2975 2775);
PAINT SKYBLUE (-2975 2775);
DISPLAY INVISIBLE (-2975 2775);
FORCEADD Q_CAP..1
(-3025 2125);
FORCEPROP 1 LAST LOCATION C2377
J 0
(-2975 2225);
DISPLAY 0.489362 (-2975 2225);
PAINT SKYBLUE (-2975 2225);
FORCEPROP 2 LAST $SEC 1
J 0
(-2975 2325);
DISPLAY 0.680851 (-2975 2325);
PAINT MONO (-2975 2325);
DISPLAY INVISIBLE (-2975 2325);
FORCEPROP 2 LAST CDS_SEC 1
J 0
(-2975 2325);
DISPLAY 1.021277 (-2975 2325);
DISPLAY INVISIBLE (-2975 2325);
FORCEPROP 1 LASTPIN (-3025 2225) $PN 1
J 0
(-3015 2205);
DISPLAY 0.489362 (-3015 2205);
FORCEPROP 1 LASTPIN (-3025 2025) $PN 2
J 0
(-3015 2005);
DISPLAY 0.489362 (-3015 2005);
FORCEPROP 1 LAST MATERIAL X6S
J 0
(-2975 2025);
DISPLAY 0.489362 (-2975 2025);
PAINT SKYBLUE (-2975 2025);
FORCEPROP 1 LAST TOLERANCE 20%
J 0
(-2975 2075);
DISPLAY 0.489362 (-2975 2075);
PAINT SKYBLUE (-2975 2075);
FORCEPROP 1 LAST VALUE 22UF
J 0
(-2975 2175);
DISPLAY 0.489362 (-2975 2175);
PAINT SKYBLUE (-2975 2175);
FORCEPROP 1 LAST VOLTAGE 4V
J 0
(-2975 2125);
DISPLAY 0.489362 (-2975 2125);
PAINT SKYBLUE (-2975 2125);
FORCEPROP 1 LAST PACK_TYPE C0402
J 0
(-2975 1925);
DISPLAY 0.489362 (-2975 1925);
PAINT SKYBLUE (-2975 1925);
FORCEPROP 2 LAST CDS_LIB pure_quanta
J 0
(-3025 2125);
PAINT MONO (-3025 2125);
DISPLAY INVISIBLE (-3025 2125);
FORCEPROP 1 LAST PATH I81
J 0
(-2975 2275);
DISPLAY 0.978723 (-2975 2275);
PAINT WHITE (-2975 2275);
DISPLAY INVISIBLE (-2975 2275);
FORCEPROP 1 LAST PART_NUMBER CH622KMEB02
J 0
(-2975 1975);
DISPLAY 0.489362 (-2975 1975);
PAINT SKYBLUE (-2975 1975);
DISPLAY INVISIBLE (-2975 1975);
FORCEADD Q_CAP..1
(-2575 2125);
FORCEPROP 1 LAST LOCATION C2383
J 0
(-2525 2225);
DISPLAY 0.489362 (-2525 2225);
PAINT SKYBLUE (-2525 2225);
FORCEPROP 2 LAST $SEC 1
J 0
(-2525 2325);
DISPLAY 0.680851 (-2525 2325);
PAINT MONO (-2525 2325);
DISPLAY INVISIBLE (-2525 2325);
FORCEPROP 2 LAST CDS_SEC 1
J 0
(-2525 2325);
DISPLAY 1.021277 (-2525 2325);
DISPLAY INVISIBLE (-2525 2325);
FORCEPROP 1 LASTPIN (-2575 2225) $PN 1
J 0
(-2565 2205);
DISPLAY 0.489362 (-2565 2205);
FORCEPROP 1 LASTPIN (-2575 2025) $PN 2
J 0
(-2565 2005);
DISPLAY 0.489362 (-2565 2005);
FORCEPROP 1 LAST MATERIAL X6S
J 0
(-2525 2025);
DISPLAY 0.489362 (-2525 2025);
PAINT SKYBLUE (-2525 2025);
FORCEPROP 1 LAST TOLERANCE 20%
J 0
(-2525 2075);
DISPLAY 0.489362 (-2525 2075);
PAINT SKYBLUE (-2525 2075);
FORCEPROP 1 LAST VALUE 22UF
J 0
(-2525 2175);
DISPLAY 0.489362 (-2525 2175);
PAINT SKYBLUE (-2525 2175);
FORCEPROP 1 LAST VOLTAGE 4V
J 0
(-2525 2125);
DISPLAY 0.489362 (-2525 2125);
PAINT SKYBLUE (-2525 2125);
FORCEPROP 1 LAST PACK_TYPE C0402
J 0
(-2525 1925);
DISPLAY 0.489362 (-2525 1925);
PAINT SKYBLUE (-2525 1925);
FORCEPROP 2 LAST CDS_LIB pure_quanta
J 0
(-2575 2125);
PAINT MONO (-2575 2125);
DISPLAY INVISIBLE (-2575 2125);
FORCEPROP 1 LAST PATH I82
J 0
(-2525 2275);
DISPLAY 0.978723 (-2525 2275);
PAINT WHITE (-2525 2275);
DISPLAY INVISIBLE (-2525 2275);
FORCEPROP 1 LAST PART_NUMBER CH622KMEB02
J 0
(-2525 1975);
DISPLAY 0.489362 (-2525 1975);
PAINT SKYBLUE (-2525 1975);
DISPLAY INVISIBLE (-2525 1975);
FORCEADD Q_CAP..1
(-2125 2125);
FORCEPROP 1 LAST LOCATION C2389
J 0
(-2075 2225);
DISPLAY 0.489362 (-2075 2225);
PAINT SKYBLUE (-2075 2225);
FORCEPROP 2 LAST $SEC 1
J 0
(-2075 2325);
DISPLAY 0.680851 (-2075 2325);
PAINT MONO (-2075 2325);
DISPLAY INVISIBLE (-2075 2325);
FORCEPROP 2 LAST CDS_SEC 1
J 0
(-2075 2325);
DISPLAY 1.021277 (-2075 2325);
DISPLAY INVISIBLE (-2075 2325);
FORCEPROP 1 LASTPIN (-2125 2225) $PN 1
J 0
(-2115 2205);
DISPLAY 0.489362 (-2115 2205);
FORCEPROP 1 LASTPIN (-2125 2025) $PN 2
J 0
(-2115 2005);
DISPLAY 0.489362 (-2115 2005);
FORCEPROP 1 LAST MATERIAL X6S
J 0
(-2075 2025);
DISPLAY 0.489362 (-2075 2025);
PAINT SKYBLUE (-2075 2025);
FORCEPROP 1 LAST TOLERANCE 20%
J 0
(-2075 2075);
DISPLAY 0.489362 (-2075 2075);
PAINT SKYBLUE (-2075 2075);
FORCEPROP 1 LAST VALUE 22UF
J 0
(-2075 2175);
DISPLAY 0.489362 (-2075 2175);
PAINT SKYBLUE (-2075 2175);
FORCEPROP 1 LAST VOLTAGE 4V
J 0
(-2075 2125);
DISPLAY 0.489362 (-2075 2125);
PAINT SKYBLUE (-2075 2125);
FORCEPROP 1 LAST PACK_TYPE C0402
J 0
(-2075 1925);
DISPLAY 0.489362 (-2075 1925);
PAINT SKYBLUE (-2075 1925);
FORCEPROP 2 LAST CDS_LIB pure_quanta
J 0
(-2125 2125);
PAINT MONO (-2125 2125);
DISPLAY INVISIBLE (-2125 2125);
FORCEPROP 1 LAST PATH I83
J 0
(-2075 2275);
DISPLAY 0.978723 (-2075 2275);
PAINT WHITE (-2075 2275);
DISPLAY INVISIBLE (-2075 2275);
FORCEPROP 1 LAST PART_NUMBER CH622KMEB02
J 0
(-2075 1975);
DISPLAY 0.489362 (-2075 1975);
PAINT SKYBLUE (-2075 1975);
DISPLAY INVISIBLE (-2075 1975);
FORCEADD Q_CAP..1
(-2575 2925);
FORCEPROP 1 LAST LOCATION C2382
J 0
(-2525 3025);
DISPLAY 0.489362 (-2525 3025);
PAINT SKYBLUE (-2525 3025);
FORCEPROP 2 LAST $SEC 1
J 0
(-2525 3125);
DISPLAY 0.680851 (-2525 3125);
PAINT MONO (-2525 3125);
DISPLAY INVISIBLE (-2525 3125);
FORCEPROP 2 LAST CDS_SEC 1
J 0
(-2525 3125);
DISPLAY 1.021277 (-2525 3125);
DISPLAY INVISIBLE (-2525 3125);
FORCEPROP 1 LASTPIN (-2575 3025) $PN 1
J 0
(-2565 3005);
DISPLAY 0.489362 (-2565 3005);
FORCEPROP 1 LASTPIN (-2575 2825) $PN 2
J 0
(-2565 2805);
DISPLAY 0.489362 (-2565 2805);
FORCEPROP 1 LAST MATERIAL X6S
J 0
(-2525 2825);
DISPLAY 0.489362 (-2525 2825);
PAINT SKYBLUE (-2525 2825);
FORCEPROP 1 LAST TOLERANCE 20%
J 0
(-2525 2875);
DISPLAY 0.489362 (-2525 2875);
PAINT SKYBLUE (-2525 2875);
FORCEPROP 1 LAST VALUE 22UF
J 0
(-2525 2975);
DISPLAY 0.489362 (-2525 2975);
PAINT SKYBLUE (-2525 2975);
FORCEPROP 1 LAST VOLTAGE 4V
J 0
(-2525 2925);
DISPLAY 0.489362 (-2525 2925);
PAINT SKYBLUE (-2525 2925);
FORCEPROP 1 LAST PACK_TYPE C0402
J 0
(-2525 2725);
DISPLAY 0.489362 (-2525 2725);
PAINT SKYBLUE (-2525 2725);
FORCEPROP 2 LAST CDS_LIB pure_quanta
J 0
(-2575 2925);
PAINT MONO (-2575 2925);
DISPLAY INVISIBLE (-2575 2925);
FORCEPROP 1 LAST PATH I84
J 0
(-2525 3075);
DISPLAY 0.978723 (-2525 3075);
PAINT WHITE (-2525 3075);
DISPLAY INVISIBLE (-2525 3075);
FORCEPROP 1 LAST PART_NUMBER CH622KMEB02
J 0
(-2525 2775);
DISPLAY 0.489362 (-2525 2775);
PAINT SKYBLUE (-2525 2775);
DISPLAY INVISIBLE (-2525 2775);
FORCEADD Q_CAP..1
(-3025 3725);
FORCEPROP 1 LAST LOCATION C2375
J 0
(-2975 3825);
DISPLAY 0.489362 (-2975 3825);
PAINT SKYBLUE (-2975 3825);
FORCEPROP 2 LAST $SEC 1
J 0
(-2975 3925);
DISPLAY 0.680851 (-2975 3925);
PAINT MONO (-2975 3925);
DISPLAY INVISIBLE (-2975 3925);
FORCEPROP 2 LAST CDS_SEC 1
J 0
(-2975 3925);
DISPLAY 1.021277 (-2975 3925);
DISPLAY INVISIBLE (-2975 3925);
FORCEPROP 1 LASTPIN (-3025 3825) $PN 1
J 0
(-3015 3805);
DISPLAY 0.489362 (-3015 3805);
FORCEPROP 1 LASTPIN (-3025 3625) $PN 2
J 0
(-3015 3605);
DISPLAY 0.489362 (-3015 3605);
FORCEPROP 1 LAST MATERIAL X6S
J 0
(-2975 3625);
DISPLAY 0.489362 (-2975 3625);
PAINT SKYBLUE (-2975 3625);
FORCEPROP 1 LAST TOLERANCE 20%
J 0
(-2975 3675);
DISPLAY 0.489362 (-2975 3675);
PAINT SKYBLUE (-2975 3675);
FORCEPROP 1 LAST VALUE 22UF
J 0
(-2975 3775);
DISPLAY 0.489362 (-2975 3775);
PAINT SKYBLUE (-2975 3775);
FORCEPROP 1 LAST VOLTAGE 4V
J 0
(-2975 3725);
DISPLAY 0.489362 (-2975 3725);
PAINT SKYBLUE (-2975 3725);
FORCEPROP 1 LAST PACK_TYPE C0402
J 0
(-2975 3525);
DISPLAY 0.489362 (-2975 3525);
PAINT SKYBLUE (-2975 3525);
FORCEPROP 2 LAST CDS_LIB pure_quanta
J 0
(-3025 3725);
PAINT MONO (-3025 3725);
DISPLAY INVISIBLE (-3025 3725);
FORCEPROP 1 LAST PATH I85
J 0
(-2975 3875);
DISPLAY 0.978723 (-2975 3875);
PAINT WHITE (-2975 3875);
DISPLAY INVISIBLE (-2975 3875);
FORCEPROP 1 LAST PART_NUMBER CH622KMEB02
J 0
(-2975 3575);
DISPLAY 0.489362 (-2975 3575);
PAINT SKYBLUE (-2975 3575);
DISPLAY INVISIBLE (-2975 3575);
FORCEADD Q_CAP..1
(-2575 3725);
FORCEPROP 1 LAST LOCATION C2381
J 0
(-2525 3825);
DISPLAY 0.489362 (-2525 3825);
PAINT SKYBLUE (-2525 3825);
FORCEPROP 2 LAST $SEC 1
J 0
(-2525 3925);
DISPLAY 0.680851 (-2525 3925);
PAINT MONO (-2525 3925);
DISPLAY INVISIBLE (-2525 3925);
FORCEPROP 2 LAST CDS_SEC 1
J 0
(-2525 3925);
DISPLAY 1.021277 (-2525 3925);
DISPLAY INVISIBLE (-2525 3925);
FORCEPROP 1 LASTPIN (-2575 3825) $PN 1
J 0
(-2565 3805);
DISPLAY 0.489362 (-2565 3805);
FORCEPROP 1 LASTPIN (-2575 3625) $PN 2
J 0
(-2565 3605);
DISPLAY 0.489362 (-2565 3605);
FORCEPROP 1 LAST MATERIAL X6S
J 0
(-2525 3625);
DISPLAY 0.489362 (-2525 3625);
PAINT SKYBLUE (-2525 3625);
FORCEPROP 1 LAST TOLERANCE 20%
J 0
(-2525 3675);
DISPLAY 0.489362 (-2525 3675);
PAINT SKYBLUE (-2525 3675);
FORCEPROP 1 LAST VALUE 22UF
J 0
(-2525 3775);
DISPLAY 0.489362 (-2525 3775);
PAINT SKYBLUE (-2525 3775);
FORCEPROP 1 LAST VOLTAGE 4V
J 0
(-2525 3725);
DISPLAY 0.489362 (-2525 3725);
PAINT SKYBLUE (-2525 3725);
FORCEPROP 1 LAST PACK_TYPE C0402
J 0
(-2525 3525);
DISPLAY 0.489362 (-2525 3525);
PAINT SKYBLUE (-2525 3525);
FORCEPROP 2 LAST CDS_LIB pure_quanta
J 0
(-2575 3725);
PAINT MONO (-2575 3725);
DISPLAY INVISIBLE (-2575 3725);
FORCEPROP 1 LAST PATH I86
J 0
(-2525 3875);
DISPLAY 0.978723 (-2525 3875);
PAINT WHITE (-2525 3875);
DISPLAY INVISIBLE (-2525 3875);
FORCEPROP 1 LAST PART_NUMBER CH622KMEB02
J 0
(-2525 3575);
DISPLAY 0.489362 (-2525 3575);
PAINT SKYBLUE (-2525 3575);
DISPLAY INVISIBLE (-2525 3575);
FORCEADD Q_CAP..1
(-2125 2925);
FORCEPROP 1 LAST LOCATION C2388
J 0
(-2075 3025);
DISPLAY 0.489362 (-2075 3025);
PAINT SKYBLUE (-2075 3025);
FORCEPROP 2 LAST $SEC 1
J 0
(-2075 3125);
DISPLAY 0.680851 (-2075 3125);
PAINT MONO (-2075 3125);
DISPLAY INVISIBLE (-2075 3125);
FORCEPROP 2 LAST CDS_SEC 1
J 0
(-2075 3125);
DISPLAY 1.021277 (-2075 3125);
DISPLAY INVISIBLE (-2075 3125);
FORCEPROP 1 LASTPIN (-2125 3025) $PN 1
J 0
(-2115 3005);
DISPLAY 0.489362 (-2115 3005);
FORCEPROP 1 LASTPIN (-2125 2825) $PN 2
J 0
(-2115 2805);
DISPLAY 0.489362 (-2115 2805);
FORCEPROP 1 LAST MATERIAL X6S
J 0
(-2075 2825);
DISPLAY 0.489362 (-2075 2825);
PAINT SKYBLUE (-2075 2825);
FORCEPROP 1 LAST TOLERANCE 20%
J 0
(-2075 2875);
DISPLAY 0.489362 (-2075 2875);
PAINT SKYBLUE (-2075 2875);
FORCEPROP 1 LAST VALUE 22UF
J 0
(-2075 2975);
DISPLAY 0.489362 (-2075 2975);
PAINT SKYBLUE (-2075 2975);
FORCEPROP 1 LAST VOLTAGE 4V
J 0
(-2075 2925);
DISPLAY 0.489362 (-2075 2925);
PAINT SKYBLUE (-2075 2925);
FORCEPROP 1 LAST PACK_TYPE C0402
J 0
(-2075 2725);
DISPLAY 0.489362 (-2075 2725);
PAINT SKYBLUE (-2075 2725);
FORCEPROP 2 LAST CDS_LIB pure_quanta
J 0
(-2125 2925);
PAINT MONO (-2125 2925);
DISPLAY INVISIBLE (-2125 2925);
FORCEPROP 1 LAST PATH I87
J 0
(-2075 3075);
DISPLAY 0.978723 (-2075 3075);
PAINT WHITE (-2075 3075);
DISPLAY INVISIBLE (-2075 3075);
FORCEPROP 1 LAST PART_NUMBER CH622KMEB02
J 0
(-2075 2775);
DISPLAY 0.489362 (-2075 2775);
PAINT SKYBLUE (-2075 2775);
DISPLAY INVISIBLE (-2075 2775);
FORCEADD Q_CAP..1
(-2125 3725);
FORCEPROP 1 LAST LOCATION C2387
J 0
(-2075 3825);
DISPLAY 0.489362 (-2075 3825);
PAINT SKYBLUE (-2075 3825);
FORCEPROP 2 LAST $SEC 1
J 0
(-2075 3925);
DISPLAY 0.680851 (-2075 3925);
PAINT MONO (-2075 3925);
DISPLAY INVISIBLE (-2075 3925);
FORCEPROP 2 LAST CDS_SEC 1
J 0
(-2075 3925);
DISPLAY 1.021277 (-2075 3925);
DISPLAY INVISIBLE (-2075 3925);
FORCEPROP 1 LASTPIN (-2125 3825) $PN 1
J 0
(-2115 3805);
DISPLAY 0.489362 (-2115 3805);
FORCEPROP 1 LASTPIN (-2125 3625) $PN 2
J 0
(-2115 3605);
DISPLAY 0.489362 (-2115 3605);
FORCEPROP 1 LAST MATERIAL X6S
J 0
(-2075 3625);
DISPLAY 0.489362 (-2075 3625);
PAINT SKYBLUE (-2075 3625);
FORCEPROP 1 LAST TOLERANCE 20%
J 0
(-2075 3675);
DISPLAY 0.489362 (-2075 3675);
PAINT SKYBLUE (-2075 3675);
FORCEPROP 1 LAST VALUE 22UF
J 0
(-2075 3775);
DISPLAY 0.489362 (-2075 3775);
PAINT SKYBLUE (-2075 3775);
FORCEPROP 1 LAST VOLTAGE 4V
J 0
(-2075 3725);
DISPLAY 0.489362 (-2075 3725);
PAINT SKYBLUE (-2075 3725);
FORCEPROP 1 LAST PACK_TYPE C0402
J 0
(-2075 3525);
DISPLAY 0.489362 (-2075 3525);
PAINT SKYBLUE (-2075 3525);
FORCEPROP 2 LAST CDS_LIB pure_quanta
J 0
(-2125 3725);
PAINT MONO (-2125 3725);
DISPLAY INVISIBLE (-2125 3725);
FORCEPROP 1 LAST PATH I88
J 0
(-2075 3875);
DISPLAY 0.978723 (-2075 3875);
PAINT WHITE (-2075 3875);
DISPLAY INVISIBLE (-2075 3875);
FORCEPROP 1 LAST PART_NUMBER CH622KMEB02
J 0
(-2075 3575);
DISPLAY 0.489362 (-2075 3575);
PAINT SKYBLUE (-2075 3575);
DISPLAY INVISIBLE (-2075 3575);
FORCEADD Q_CAP..1
(-1675 2125);
FORCEPROP 1 LAST LOCATION C2395
J 0
(-1625 2225);
DISPLAY 0.489362 (-1625 2225);
PAINT SKYBLUE (-1625 2225);
FORCEPROP 2 LAST $SEC 1
J 0
(-1625 2325);
DISPLAY 0.680851 (-1625 2325);
PAINT MONO (-1625 2325);
DISPLAY INVISIBLE (-1625 2325);
FORCEPROP 2 LAST CDS_SEC 1
J 0
(-1625 2325);
DISPLAY 1.021277 (-1625 2325);
DISPLAY INVISIBLE (-1625 2325);
FORCEPROP 1 LASTPIN (-1675 2225) $PN 1
J 0
(-1665 2205);
DISPLAY 0.489362 (-1665 2205);
FORCEPROP 1 LASTPIN (-1675 2025) $PN 2
J 0
(-1665 2005);
DISPLAY 0.489362 (-1665 2005);
FORCEPROP 1 LAST MATERIAL X6S
J 0
(-1625 2025);
DISPLAY 0.489362 (-1625 2025);
PAINT SKYBLUE (-1625 2025);
FORCEPROP 1 LAST TOLERANCE 20%
J 0
(-1625 2075);
DISPLAY 0.489362 (-1625 2075);
PAINT SKYBLUE (-1625 2075);
FORCEPROP 1 LAST VALUE 22UF
J 0
(-1625 2175);
DISPLAY 0.489362 (-1625 2175);
PAINT SKYBLUE (-1625 2175);
FORCEPROP 1 LAST VOLTAGE 4V
J 0
(-1625 2125);
DISPLAY 0.489362 (-1625 2125);
PAINT SKYBLUE (-1625 2125);
FORCEPROP 1 LAST PACK_TYPE C0402
J 0
(-1625 1925);
DISPLAY 0.489362 (-1625 1925);
PAINT SKYBLUE (-1625 1925);
FORCEPROP 2 LAST CDS_LIB pure_quanta
J 0
(-1675 2125);
PAINT MONO (-1675 2125);
DISPLAY INVISIBLE (-1675 2125);
FORCEPROP 1 LAST PATH I89
J 0
(-1625 2275);
DISPLAY 0.978723 (-1625 2275);
PAINT WHITE (-1625 2275);
DISPLAY INVISIBLE (-1625 2275);
FORCEPROP 1 LAST PART_NUMBER CH622KMEB02
J 0
(-1625 1975);
DISPLAY 0.489362 (-1625 1975);
PAINT SKYBLUE (-1625 1975);
DISPLAY INVISIBLE (-1625 1975);
FORCEADD Q_CAP..1
(-9400 3725);
FORCEPROP 1 LAST LOCATION C2295
J 0
(-9350 3825);
DISPLAY 0.489362 (-9350 3825);
PAINT SKYBLUE (-9350 3825);
FORCEPROP 2 LAST $SEC 1
J 0
(-9350 3925);
DISPLAY 0.680851 (-9350 3925);
PAINT MONO (-9350 3925);
DISPLAY INVISIBLE (-9350 3925);
FORCEPROP 2 LAST CDS_SEC 1
J 0
(-9350 3925);
DISPLAY 1.021277 (-9350 3925);
DISPLAY INVISIBLE (-9350 3925);
FORCEPROP 1 LASTPIN (-9400 3825) $PN 1
J 0
(-9390 3805);
DISPLAY 0.489362 (-9390 3805);
FORCEPROP 1 LASTPIN (-9400 3625) $PN 2
J 0
(-9390 3605);
DISPLAY 0.489362 (-9390 3605);
FORCEPROP 1 LAST MATERIAL X6S
J 0
(-9350 3625);
DISPLAY 0.489362 (-9350 3625);
PAINT SKYBLUE (-9350 3625);
FORCEPROP 1 LAST TOLERANCE 20%
J 0
(-9350 3675);
DISPLAY 0.489362 (-9350 3675);
PAINT SKYBLUE (-9350 3675);
FORCEPROP 1 LAST VALUE 22UF
J 0
(-9350 3775);
DISPLAY 0.489362 (-9350 3775);
PAINT SKYBLUE (-9350 3775);
FORCEPROP 1 LAST VOLTAGE 4V
J 0
(-9350 3725);
DISPLAY 0.489362 (-9350 3725);
PAINT SKYBLUE (-9350 3725);
FORCEPROP 1 LAST PACK_TYPE C0402
J 0
(-9350 3525);
DISPLAY 0.489362 (-9350 3525);
PAINT SKYBLUE (-9350 3525);
FORCEPROP 2 LAST CDS_LIB pure_quanta
J 0
(-9400 3725);
PAINT MONO (-9400 3725);
DISPLAY INVISIBLE (-9400 3725);
FORCEPROP 1 LAST PATH I9
J 0
(-9350 3875);
DISPLAY 0.978723 (-9350 3875);
PAINT WHITE (-9350 3875);
DISPLAY INVISIBLE (-9350 3875);
FORCEPROP 1 LAST PART_NUMBER CH622KMEB02
J 0
(-9350 3575);
DISPLAY 0.489362 (-9350 3575);
PAINT SKYBLUE (-9350 3575);
DISPLAY INVISIBLE (-9350 3575);
FORCEADD Q_CAP..1
(-1225 2125);
FORCEPROP 1 LAST LOCATION C2400
J 0
(-1175 2225);
DISPLAY 0.489362 (-1175 2225);
PAINT SKYBLUE (-1175 2225);
FORCEPROP 2 LAST $SEC 1
J 0
(-1175 2325);
DISPLAY 0.680851 (-1175 2325);
PAINT MONO (-1175 2325);
DISPLAY INVISIBLE (-1175 2325);
FORCEPROP 2 LAST CDS_SEC 1
J 0
(-1175 2325);
DISPLAY 1.021277 (-1175 2325);
DISPLAY INVISIBLE (-1175 2325);
FORCEPROP 1 LASTPIN (-1225 2225) $PN 1
J 0
(-1215 2205);
DISPLAY 0.489362 (-1215 2205);
FORCEPROP 1 LASTPIN (-1225 2025) $PN 2
J 0
(-1215 2005);
DISPLAY 0.489362 (-1215 2005);
FORCEPROP 1 LAST MATERIAL X6S
J 0
(-1175 2025);
DISPLAY 0.489362 (-1175 2025);
PAINT SKYBLUE (-1175 2025);
FORCEPROP 1 LAST TOLERANCE 20%
J 0
(-1175 2075);
DISPLAY 0.489362 (-1175 2075);
PAINT SKYBLUE (-1175 2075);
FORCEPROP 1 LAST VALUE 22UF
J 0
(-1175 2175);
DISPLAY 0.489362 (-1175 2175);
PAINT SKYBLUE (-1175 2175);
FORCEPROP 1 LAST VOLTAGE 4V
J 0
(-1175 2125);
DISPLAY 0.489362 (-1175 2125);
PAINT SKYBLUE (-1175 2125);
FORCEPROP 1 LAST PACK_TYPE C0402
J 0
(-1175 1925);
DISPLAY 0.489362 (-1175 1925);
PAINT SKYBLUE (-1175 1925);
FORCEPROP 2 LAST CDS_LIB pure_quanta
J 0
(-1225 2125);
PAINT MONO (-1225 2125);
DISPLAY INVISIBLE (-1225 2125);
FORCEPROP 1 LAST PATH I90
J 0
(-1175 2275);
DISPLAY 0.978723 (-1175 2275);
PAINT WHITE (-1175 2275);
DISPLAY INVISIBLE (-1175 2275);
FORCEPROP 1 LAST PART_NUMBER CH622KMEB02
J 0
(-1175 1975);
DISPLAY 0.489362 (-1175 1975);
PAINT SKYBLUE (-1175 1975);
DISPLAY INVISIBLE (-1175 1975);
FORCEADD Q_CAP..1
(-1675 2925);
FORCEPROP 1 LAST LOCATION C2394
J 0
(-1625 3025);
DISPLAY 0.489362 (-1625 3025);
PAINT SKYBLUE (-1625 3025);
FORCEPROP 2 LAST $SEC 1
J 0
(-1625 3125);
DISPLAY 0.680851 (-1625 3125);
PAINT MONO (-1625 3125);
DISPLAY INVISIBLE (-1625 3125);
FORCEPROP 2 LAST CDS_SEC 1
J 0
(-1625 3125);
DISPLAY 1.021277 (-1625 3125);
DISPLAY INVISIBLE (-1625 3125);
FORCEPROP 1 LASTPIN (-1675 3025) $PN 1
J 0
(-1665 3005);
DISPLAY 0.489362 (-1665 3005);
FORCEPROP 1 LASTPIN (-1675 2825) $PN 2
J 0
(-1665 2805);
DISPLAY 0.489362 (-1665 2805);
FORCEPROP 1 LAST MATERIAL X6S
J 0
(-1625 2825);
DISPLAY 0.489362 (-1625 2825);
PAINT SKYBLUE (-1625 2825);
FORCEPROP 1 LAST TOLERANCE 20%
J 0
(-1625 2875);
DISPLAY 0.489362 (-1625 2875);
PAINT SKYBLUE (-1625 2875);
FORCEPROP 1 LAST VALUE 22UF
J 0
(-1625 2975);
DISPLAY 0.489362 (-1625 2975);
PAINT SKYBLUE (-1625 2975);
FORCEPROP 1 LAST VOLTAGE 4V
J 0
(-1625 2925);
DISPLAY 0.489362 (-1625 2925);
PAINT SKYBLUE (-1625 2925);
FORCEPROP 1 LAST PACK_TYPE C0402
J 0
(-1625 2725);
DISPLAY 0.489362 (-1625 2725);
PAINT SKYBLUE (-1625 2725);
FORCEPROP 2 LAST CDS_LIB pure_quanta
J 0
(-1675 2925);
PAINT MONO (-1675 2925);
DISPLAY INVISIBLE (-1675 2925);
FORCEPROP 1 LAST PATH I91
J 0
(-1625 3075);
DISPLAY 0.978723 (-1625 3075);
PAINT WHITE (-1625 3075);
DISPLAY INVISIBLE (-1625 3075);
FORCEPROP 1 LAST PART_NUMBER CH622KMEB02
J 0
(-1625 2775);
DISPLAY 0.489362 (-1625 2775);
PAINT SKYBLUE (-1625 2775);
DISPLAY INVISIBLE (-1625 2775);
FORCEADD Q_CAP..1
(-1675 3725);
FORCEPROP 1 LAST LOCATION C2393
J 0
(-1625 3825);
DISPLAY 0.489362 (-1625 3825);
PAINT SKYBLUE (-1625 3825);
FORCEPROP 2 LAST $SEC 1
J 0
(-1625 3925);
DISPLAY 0.680851 (-1625 3925);
PAINT MONO (-1625 3925);
DISPLAY INVISIBLE (-1625 3925);
FORCEPROP 2 LAST CDS_SEC 1
J 0
(-1625 3925);
DISPLAY 1.021277 (-1625 3925);
DISPLAY INVISIBLE (-1625 3925);
FORCEPROP 1 LASTPIN (-1675 3825) $PN 1
J 0
(-1665 3805);
DISPLAY 0.489362 (-1665 3805);
FORCEPROP 1 LASTPIN (-1675 3625) $PN 2
J 0
(-1665 3605);
DISPLAY 0.489362 (-1665 3605);
FORCEPROP 1 LAST MATERIAL X6S
J 0
(-1625 3625);
DISPLAY 0.489362 (-1625 3625);
PAINT SKYBLUE (-1625 3625);
FORCEPROP 1 LAST TOLERANCE 20%
J 0
(-1625 3675);
DISPLAY 0.489362 (-1625 3675);
PAINT SKYBLUE (-1625 3675);
FORCEPROP 1 LAST VALUE 22UF
J 0
(-1625 3775);
DISPLAY 0.489362 (-1625 3775);
PAINT SKYBLUE (-1625 3775);
FORCEPROP 1 LAST VOLTAGE 4V
J 0
(-1625 3725);
DISPLAY 0.489362 (-1625 3725);
PAINT SKYBLUE (-1625 3725);
FORCEPROP 1 LAST PACK_TYPE C0402
J 0
(-1625 3525);
DISPLAY 0.489362 (-1625 3525);
PAINT SKYBLUE (-1625 3525);
FORCEPROP 2 LAST CDS_LIB pure_quanta
J 0
(-1675 3725);
PAINT MONO (-1675 3725);
DISPLAY INVISIBLE (-1675 3725);
FORCEPROP 1 LAST PATH I92
J 0
(-1625 3875);
DISPLAY 0.978723 (-1625 3875);
PAINT WHITE (-1625 3875);
DISPLAY INVISIBLE (-1625 3875);
FORCEPROP 1 LAST PART_NUMBER CH622KMEB02
J 0
(-1625 3575);
DISPLAY 0.489362 (-1625 3575);
PAINT SKYBLUE (-1625 3575);
DISPLAY INVISIBLE (-1625 3575);
FORCEADD Q_CAP..1
(-1225 2925);
FORCEPROP 1 LAST LOCATION C2399
J 0
(-1175 3025);
DISPLAY 0.489362 (-1175 3025);
PAINT SKYBLUE (-1175 3025);
FORCEPROP 2 LAST $SEC 1
J 0
(-1175 3125);
DISPLAY 0.680851 (-1175 3125);
PAINT MONO (-1175 3125);
DISPLAY INVISIBLE (-1175 3125);
FORCEPROP 2 LAST CDS_SEC 1
J 0
(-1175 3125);
DISPLAY 1.021277 (-1175 3125);
DISPLAY INVISIBLE (-1175 3125);
FORCEPROP 1 LASTPIN (-1225 3025) $PN 1
J 0
(-1215 3005);
DISPLAY 0.489362 (-1215 3005);
FORCEPROP 1 LASTPIN (-1225 2825) $PN 2
J 0
(-1215 2805);
DISPLAY 0.489362 (-1215 2805);
FORCEPROP 1 LAST MATERIAL X6S
J 0
(-1175 2825);
DISPLAY 0.489362 (-1175 2825);
PAINT SKYBLUE (-1175 2825);
FORCEPROP 1 LAST TOLERANCE 20%
J 0
(-1175 2875);
DISPLAY 0.489362 (-1175 2875);
PAINT SKYBLUE (-1175 2875);
FORCEPROP 1 LAST VALUE 22UF
J 0
(-1175 2975);
DISPLAY 0.489362 (-1175 2975);
PAINT SKYBLUE (-1175 2975);
FORCEPROP 1 LAST VOLTAGE 4V
J 0
(-1175 2925);
DISPLAY 0.489362 (-1175 2925);
PAINT SKYBLUE (-1175 2925);
FORCEPROP 1 LAST PACK_TYPE C0402
J 0
(-1175 2725);
DISPLAY 0.489362 (-1175 2725);
PAINT SKYBLUE (-1175 2725);
FORCEPROP 2 LAST CDS_LIB pure_quanta
J 0
(-1225 2925);
PAINT MONO (-1225 2925);
DISPLAY INVISIBLE (-1225 2925);
FORCEPROP 1 LAST PATH I93
J 0
(-1175 3075);
DISPLAY 0.978723 (-1175 3075);
PAINT WHITE (-1175 3075);
DISPLAY INVISIBLE (-1175 3075);
FORCEPROP 1 LAST PART_NUMBER CH622KMEB02
J 0
(-1175 2775);
DISPLAY 0.489362 (-1175 2775);
PAINT SKYBLUE (-1175 2775);
DISPLAY INVISIBLE (-1175 2775);
FORCEADD Q_CAP..1
(-1225 3725);
FORCEPROP 1 LAST LOCATION C2398
J 0
(-1175 3825);
DISPLAY 0.489362 (-1175 3825);
PAINT SKYBLUE (-1175 3825);
FORCEPROP 2 LAST $SEC 1
J 0
(-1175 3925);
DISPLAY 0.680851 (-1175 3925);
PAINT MONO (-1175 3925);
DISPLAY INVISIBLE (-1175 3925);
FORCEPROP 2 LAST CDS_SEC 1
J 0
(-1175 3925);
DISPLAY 1.021277 (-1175 3925);
DISPLAY INVISIBLE (-1175 3925);
FORCEPROP 1 LASTPIN (-1225 3825) $PN 1
J 0
(-1215 3805);
DISPLAY 0.489362 (-1215 3805);
FORCEPROP 1 LASTPIN (-1225 3625) $PN 2
J 0
(-1215 3605);
DISPLAY 0.489362 (-1215 3605);
FORCEPROP 1 LAST MATERIAL X6S
J 0
(-1175 3625);
DISPLAY 0.489362 (-1175 3625);
PAINT SKYBLUE (-1175 3625);
FORCEPROP 1 LAST TOLERANCE 20%
J 0
(-1175 3675);
DISPLAY 0.489362 (-1175 3675);
PAINT SKYBLUE (-1175 3675);
FORCEPROP 1 LAST VALUE 22UF
J 0
(-1175 3775);
DISPLAY 0.489362 (-1175 3775);
PAINT SKYBLUE (-1175 3775);
FORCEPROP 1 LAST VOLTAGE 4V
J 0
(-1175 3725);
DISPLAY 0.489362 (-1175 3725);
PAINT SKYBLUE (-1175 3725);
FORCEPROP 1 LAST PACK_TYPE C0402
J 0
(-1175 3525);
DISPLAY 0.489362 (-1175 3525);
PAINT SKYBLUE (-1175 3525);
FORCEPROP 2 LAST CDS_LIB pure_quanta
J 0
(-1225 3725);
PAINT MONO (-1225 3725);
DISPLAY INVISIBLE (-1225 3725);
FORCEPROP 1 LAST PATH I94
J 0
(-1175 3875);
DISPLAY 0.978723 (-1175 3875);
PAINT WHITE (-1175 3875);
DISPLAY INVISIBLE (-1175 3875);
FORCEPROP 1 LAST PART_NUMBER CH622KMEB02
J 0
(-1175 3575);
DISPLAY 0.489362 (-1175 3575);
PAINT SKYBLUE (-1175 3575);
DISPLAY INVISIBLE (-1175 3575);
FORCEADD UNIVERSAL_GND..1
(-825 1750);
FORCEPROP 3 LASTPIN (-825 1800) SIG_NAME GND\g
J 0
(-815 1810);
DISPLAY 0.659574 (-815 1810);
PAINT MONO (-815 1810);
DISPLAY INVISIBLE (-815 1810);
FORCEPROP 2 LAST CDS_LIB pure_quanta_power
J 0
(-825 1750);
PAINT MONO (-825 1750);
DISPLAY INVISIBLE (-825 1750);
FORCEPROP 1 LAST HDL_POWER GND
J 1
(-800 1675);
DISPLAY 0.872340 (-800 1675);
PAINT GREEN (-800 1675);
DISPLAY INVISIBLE (-800 1675);
FORCEPROP 1 LAST PATH I95
J 0
(-750 1750);
DISPLAY 0.872340 (-750 1750);
PAINT AQUA (-750 1750);
DISPLAY INVISIBLE (-750 1750);
FORCEADD Q_CAP..1
(-825 2125);
FORCEPROP 1 LAST LOCATION C2405
J 0
(-775 2225);
DISPLAY 0.489362 (-775 2225);
PAINT SKYBLUE (-775 2225);
FORCEPROP 2 LAST $SEC 1
J 0
(-775 2325);
DISPLAY 0.680851 (-775 2325);
PAINT MONO (-775 2325);
DISPLAY INVISIBLE (-775 2325);
FORCEPROP 2 LAST CDS_SEC 1
J 0
(-775 2325);
DISPLAY 1.021277 (-775 2325);
DISPLAY INVISIBLE (-775 2325);
FORCEPROP 1 LASTPIN (-825 2225) $PN 1
J 0
(-815 2205);
DISPLAY 0.489362 (-815 2205);
FORCEPROP 1 LASTPIN (-825 2025) $PN 2
J 0
(-815 2005);
DISPLAY 0.489362 (-815 2005);
FORCEPROP 1 LAST MATERIAL X6S
J 0
(-775 2025);
DISPLAY 0.489362 (-775 2025);
PAINT SKYBLUE (-775 2025);
FORCEPROP 1 LAST TOLERANCE 20%
J 0
(-775 2075);
DISPLAY 0.489362 (-775 2075);
PAINT SKYBLUE (-775 2075);
FORCEPROP 1 LAST VALUE 22UF
J 0
(-775 2175);
DISPLAY 0.489362 (-775 2175);
PAINT SKYBLUE (-775 2175);
FORCEPROP 1 LAST VOLTAGE 4V
J 0
(-775 2125);
DISPLAY 0.489362 (-775 2125);
PAINT SKYBLUE (-775 2125);
FORCEPROP 1 LAST PACK_TYPE C0402
J 0
(-775 1925);
DISPLAY 0.489362 (-775 1925);
PAINT SKYBLUE (-775 1925);
FORCEPROP 2 LAST CDS_LIB pure_quanta
J 0
(-825 2125);
PAINT MONO (-825 2125);
DISPLAY INVISIBLE (-825 2125);
FORCEPROP 1 LAST PATH I96
J 0
(-775 2275);
DISPLAY 0.978723 (-775 2275);
PAINT WHITE (-775 2275);
DISPLAY INVISIBLE (-775 2275);
FORCEPROP 1 LAST PART_NUMBER CH622KMEB02
J 0
(-775 1975);
DISPLAY 0.489362 (-775 1975);
PAINT SKYBLUE (-775 1975);
DISPLAY INVISIBLE (-775 1975);
FORCEADD UNIVERSAL_GND..1
(-825 2550);
FORCEPROP 3 LASTPIN (-825 2600) SIG_NAME GND\g
J 0
(-815 2610);
DISPLAY 0.659574 (-815 2610);
PAINT MONO (-815 2610);
DISPLAY INVISIBLE (-815 2610);
FORCEPROP 2 LAST CDS_LIB pure_quanta_power
J 0
(-825 2550);
PAINT MONO (-825 2550);
DISPLAY INVISIBLE (-825 2550);
FORCEPROP 1 LAST HDL_POWER GND
J 1
(-800 2475);
DISPLAY 0.872340 (-800 2475);
PAINT GREEN (-800 2475);
DISPLAY INVISIBLE (-800 2475);
FORCEPROP 1 LAST PATH I97
J 0
(-750 2550);
DISPLAY 0.872340 (-750 2550);
PAINT AQUA (-750 2550);
DISPLAY INVISIBLE (-750 2550);
FORCEADD Q_CAP..1
(-825 2925);
FORCEPROP 1 LAST LOCATION C2404
J 0
(-775 3025);
DISPLAY 0.489362 (-775 3025);
PAINT SKYBLUE (-775 3025);
FORCEPROP 2 LAST $SEC 1
J 0
(-775 3125);
DISPLAY 0.680851 (-775 3125);
PAINT MONO (-775 3125);
DISPLAY INVISIBLE (-775 3125);
FORCEPROP 2 LAST CDS_SEC 1
J 0
(-775 3125);
DISPLAY 1.021277 (-775 3125);
DISPLAY INVISIBLE (-775 3125);
FORCEPROP 1 LASTPIN (-825 3025) $PN 1
J 0
(-815 3005);
DISPLAY 0.489362 (-815 3005);
FORCEPROP 1 LASTPIN (-825 2825) $PN 2
J 0
(-815 2805);
DISPLAY 0.489362 (-815 2805);
FORCEPROP 1 LAST MATERIAL X6S
J 0
(-775 2825);
DISPLAY 0.489362 (-775 2825);
PAINT SKYBLUE (-775 2825);
FORCEPROP 1 LAST TOLERANCE 20%
J 0
(-775 2875);
DISPLAY 0.489362 (-775 2875);
PAINT SKYBLUE (-775 2875);
FORCEPROP 1 LAST VALUE 22UF
J 0
(-775 2975);
DISPLAY 0.489362 (-775 2975);
PAINT SKYBLUE (-775 2975);
FORCEPROP 1 LAST VOLTAGE 4V
J 0
(-775 2925);
DISPLAY 0.489362 (-775 2925);
PAINT SKYBLUE (-775 2925);
FORCEPROP 1 LAST PACK_TYPE C0402
J 0
(-775 2725);
DISPLAY 0.489362 (-775 2725);
PAINT SKYBLUE (-775 2725);
FORCEPROP 2 LAST CDS_LIB pure_quanta
J 0
(-825 2925);
PAINT MONO (-825 2925);
DISPLAY INVISIBLE (-825 2925);
FORCEPROP 1 LAST PATH I98
J 0
(-775 3075);
DISPLAY 0.978723 (-775 3075);
PAINT WHITE (-775 3075);
DISPLAY INVISIBLE (-775 3075);
FORCEPROP 1 LAST PART_NUMBER CH622KMEB02
J 0
(-775 2775);
DISPLAY 0.489362 (-775 2775);
PAINT SKYBLUE (-775 2775);
DISPLAY INVISIBLE (-775 2775);
FORCEADD UNIVERSAL_GND..1
(-825 3350);
FORCEPROP 3 LASTPIN (-825 3400) SIG_NAME GND\g
J 0
(-815 3410);
DISPLAY 0.659574 (-815 3410);
PAINT MONO (-815 3410);
DISPLAY INVISIBLE (-815 3410);
FORCEPROP 2 LAST CDS_LIB pure_quanta_power
J 0
(-825 3350);
PAINT MONO (-825 3350);
DISPLAY INVISIBLE (-825 3350);
FORCEPROP 1 LAST HDL_POWER GND
J 1
(-800 3275);
DISPLAY 0.872340 (-800 3275);
PAINT GREEN (-800 3275);
DISPLAY INVISIBLE (-800 3275);
FORCEPROP 1 LAST PATH I99
J 0
(-750 3350);
DISPLAY 0.872340 (-750 3350);
PAINT AQUA (-750 3350);
DISPLAY INVISIBLE (-750 3350);
FORCEADD QUANTA_TITLE_BLOCK_C..1
(-400 -525);
FORCEPROP 0 LAST CDS_CON_LAST_MODIFIED Thu Sep 14 16:12:04 2023
J 0
(-2285 -510);
DISPLAY INVISIBLE (-2285 -510);
FORCEPROP 1 LAST CUSTOM_TXT_CDS <CON_LAST_MODIFIED>
J 0
(-2285 -510);
DISPLAY 0.978723 (-2285 -510);
FORCEPROP 2 LAST CUSTOM_TXT_CDS <XR_PAGE_TITLE>
J 0
(-8290 4725);
DISPLAY 0.638298 (-8290 4725);
PAINT PINK (-8290 4725);
DISPLAY INVISIBLE (-8290 4725);
FORCEPROP 1 LAST CUSTOM_TXT_CDS <NAME_2>
J 0
(-3575 -475);
FORCEPROP 1 LAST CUSTOM_TXT_CDS <NAME_1>
J 0
(-3575 -350);
FORCEPROP 1 LAST CUSTOM_TXT_CDS <Q_NUMBER>
J 0
(-1803 -422);
DISPLAY 1.212766 (-1803 -422);
FORCEPROP 1 LAST CUSTOM_TXT_CDS <Q_PROJ>
J 0
(-2782 -423);
DISPLAY 1.212766 (-2782 -423);
FORCEPROP 1 LAST CUSTOM_TXT_CDS <Q_REV>
J 0
(-584 -422);
DISPLAY 1.212766 (-584 -422);
FORCEPROP 1 LAST CUSTOM_TXT_CDS <CON_PAGE_NUM> OF <CON_TOTAL_PAGES>
J 0
(-846 -507);
DISPLAY 0.978723 (-846 -507);
FORCEPROP 1 LAST Q_TITLE CPU1 CAVITY BOT DECOUPLING CAPS 1/3
J 0
(-9766 -499);
DISPLAY 2.446809 (-9766 -499);
PAINT GREEN (-9766 -499);
FORCEPROP 2 LAST PAGE_BORDER TRUE
J 0
(-8290 4725);
DISPLAY 0.638298 (-8290 4725);
PAINT PINK (-8290 4725);
DISPLAY INVISIBLE (-8290 4725);
FORCEPROP 1 LAST CDS_LMAN_SYM_OUTLINE -9475,6775,100,-125
J 0
(-400 -525);
DISPLAY 0.468085 (-400 -525);
PAINT GREEN (-400 -525);
DISPLAY INVISIBLE (-400 -525);
FORCEPROP 2 LAST CDS_LIB pure_quanta
J 0
(-400 -525);
DISPLAY INVISIBLE (-400 -525);
FORCEPROP 2 LAST CDS_XR_PAGE_TITLE CR-73 : @T6G_MB_LIB.T6G(SCH_1):PAGE73
J 0
(-8290 4725);
DISPLAY 0.638298 (-8290 4725);
PAINT PINK (-8290 4725);
DISPLAY INVISIBLE (-8290 4725);
FORCEPROP 1 LAST Q_DEPT BU9
J 1
(-4163 -476);
DISPLAY 1.957447 (-4163 -476);
PAINT GREEN (-4163 -476);
DISPLAY INVISIBLE (-4163 -476);
FORCEPROP 1 LAST COMMENT_BODY TRUE
J 0
(-388 -538);
DISPLAY 0.978723 (-388 -538);
PAINT GREEN (-388 -538);
DISPLAY INVISIBLE (-388 -538);
WIRE 16 -1 (-8500 1900)(-8950 1900);
WIRE 16 -1 (-8050 1900)(-8500 1900);
WIRE 16 -1 (-8500 1900)(-8500 2025);
WIRE 16 -1 (-8950 1900)(-8950 2025);
WIRE 16 -1 (-8950 1900)(-9400 1900);
WIRE 16 -1 (-9400 1900)(-9400 2025);
WIRE 16 -1 (-7600 1900)(-8050 1900);
WIRE 16 -1 (-8050 1900)(-8050 2025);
WIRE 16 -1 (-7150 1900)(-7600 1900);
WIRE 16 -1 (-7600 1900)(-7600 2025);
WIRE 16 -1 (-6700 1900)(-7150 1900);
WIRE 16 -1 (-7150 1900)(-7150 2025);
WIRE 16 -1 (-6250 1900)(-6700 1900);
WIRE 16 -1 (-6700 1900)(-6700 2025);
WIRE 16 -1 (-5800 1900)(-6250 1900);
WIRE 16 -1 (-6250 1900)(-6250 2025);
WIRE 16 -1 (-5800 1900)(-5400 1900);
WIRE 16 -1 (-5800 1900)(-5800 2025);
WIRE 16 -1 (-5400 1800)(-5400 1900);
WIRE 16 -1 (-5400 1900)(-5400 2025);
WIRE 16 -1 (-8050 1500)(-8500 1500);
WIRE 16 -1 (-7600 1500)(-8050 1500);
WIRE 16 -1 (-8050 1425)(-8050 1500);
WIRE 16 -1 (-8500 1500)(-8500 1425);
WIRE 16 -1 (-8500 1500)(-8950 1500);
WIRE 16 -1 (-8950 1425)(-8950 1500);
WIRE 16 -1 (-8950 1500)(-9400 1500);
WIRE 16 -1 (-7600 1425)(-7600 1500);
WIRE 16 -1 (-9400 1500)(-9400 1550);
WIRE 16 -1 (-9400 1500)(-9400 1425);
WIRE 16 -1 (-8500 1100)(-8950 1100);
WIRE 16 -1 (-8050 1100)(-8500 1100);
WIRE 16 -1 (-8500 1100)(-8500 1225);
WIRE 16 -1 (-8950 1100)(-8950 1225);
WIRE 16 -1 (-8950 1100)(-9400 1100);
WIRE 16 -1 (-9400 1100)(-9400 1225);
WIRE 16 -1 (-7600 1100)(-8050 1100);
WIRE 16 -1 (-8050 1100)(-8050 1225);
WIRE 16 -1 (-7600 1100)(-7600 1225);
WIRE 16 -1 (-7600 1000)(-7600 1100);
WIRE 16 -1 (-8050 2300)(-8500 2300);
WIRE 16 -1 (-7600 2300)(-8050 2300);
WIRE 16 -1 (-8050 2225)(-8050 2300);
WIRE 16 -1 (-8500 2300)(-8500 2225);
WIRE 16 -1 (-8500 2300)(-8950 2300);
WIRE 16 -1 (-8950 2225)(-8950 2300);
WIRE 16 -1 (-8950 2300)(-9400 2300);
WIRE 16 -1 (-7150 2300)(-7600 2300);
WIRE 16 -1 (-7600 2225)(-7600 2300);
WIRE 16 -1 (-6700 2300)(-7150 2300);
WIRE 16 -1 (-7150 2300)(-7150 2225);
WIRE 16 -1 (-9400 2300)(-9400 2350);
WIRE 16 -1 (-9400 2300)(-9400 2225);
WIRE 16 -1 (-6250 2300)(-6700 2300);
WIRE 16 -1 (-6700 2225)(-6700 2300);
WIRE 16 -1 (-5800 2300)(-6250 2300);
WIRE 16 -1 (-6250 2225)(-6250 2300);
WIRE 16 -1 (-5400 2300)(-5800 2300);
WIRE 16 -1 (-5800 2300)(-5800 2225);
WIRE 16 -1 (-5400 2225)(-5400 2300);
WIRE 16 -1 (-8050 3100)(-8500 3100);
WIRE 16 -1 (-7600 3100)(-8050 3100);
WIRE 16 -1 (-8050 3025)(-8050 3100);
WIRE 16 -1 (-8500 3100)(-8950 3100);
WIRE 16 -1 (-8500 3100)(-8500 3025);
WIRE 16 -1 (-8950 3025)(-8950 3100);
WIRE 16 -1 (-8950 3100)(-9400 3100);
WIRE 16 -1 (-7150 3100)(-7600 3100);
WIRE 16 -1 (-7600 3025)(-7600 3100);
WIRE 16 -1 (-6700 3100)(-7150 3100);
WIRE 16 -1 (-7150 3100)(-7150 3025);
WIRE 16 -1 (-9400 3100)(-9400 3150);
WIRE 16 -1 (-9400 3100)(-9400 3025);
WIRE 16 -1 (-6250 3100)(-6700 3100);
WIRE 16 -1 (-6700 3025)(-6700 3100);
WIRE 16 -1 (-5800 3100)(-6250 3100);
WIRE 16 -1 (-6250 3025)(-6250 3100);
WIRE 16 -1 (-5400 3100)(-5800 3100);
WIRE 16 -1 (-5800 3100)(-5800 3025);
WIRE 16 -1 (-5400 3025)(-5400 3100);
WIRE 16 -1 (-8500 2700)(-8950 2700);
WIRE 16 -1 (-8050 2700)(-8500 2700);
WIRE 16 -1 (-8500 2700)(-8500 2825);
WIRE 16 -1 (-8950 2700)(-8950 2825);
WIRE 16 -1 (-8950 2700)(-9400 2700);
WIRE 16 -1 (-9400 2700)(-9400 2825);
WIRE 16 -1 (-7600 2700)(-8050 2700);
WIRE 16 -1 (-8050 2700)(-8050 2825);
WIRE 16 -1 (-7150 2700)(-7600 2700);
WIRE 16 -1 (-7600 2700)(-7600 2825);
WIRE 16 -1 (-6700 2700)(-7150 2700);
WIRE 16 -1 (-7150 2700)(-7150 2825);
WIRE 16 -1 (-6250 2700)(-6700 2700);
WIRE 16 -1 (-6700 2700)(-6700 2825);
WIRE 16 -1 (-5800 2700)(-6250 2700);
WIRE 16 -1 (-6250 2700)(-6250 2825);
WIRE 16 -1 (-5800 2700)(-5400 2700);
WIRE 16 -1 (-5800 2700)(-5800 2825);
WIRE 16 -1 (-5400 2700)(-5400 2825);
WIRE 16 -1 (-5400 2600)(-5400 2700);
WIRE 16 -1 (-8050 3900)(-8500 3900);
WIRE 16 -1 (-7600 3900)(-8050 3900);
WIRE 16 -1 (-8050 3825)(-8050 3900);
WIRE 16 -1 (-8500 3900)(-8500 3825);
WIRE 16 -1 (-8500 3900)(-8950 3900);
WIRE 16 -1 (-8950 3825)(-8950 3900);
WIRE 16 -1 (-8950 3900)(-9400 3900);
WIRE 16 -1 (-7150 3900)(-7600 3900);
WIRE 16 -1 (-7600 3825)(-7600 3900);
WIRE 16 -1 (-6700 3900)(-7150 3900);
WIRE 16 -1 (-7150 3900)(-7150 3825);
WIRE 16 -1 (-9400 3900)(-9400 3950);
WIRE 16 -1 (-9400 3900)(-9400 3825);
WIRE 16 -1 (-6250 3900)(-6700 3900);
WIRE 16 -1 (-6700 3825)(-6700 3900);
WIRE 16 -1 (-5800 3900)(-6250 3900);
WIRE 16 -1 (-6250 3825)(-6250 3900);
WIRE 16 -1 (-5400 3900)(-5800 3900);
WIRE 16 -1 (-5800 3900)(-5800 3825);
WIRE 16 -1 (-5400 3825)(-5400 3900);
WIRE 16 -1 (-8500 3500)(-8950 3500);
WIRE 16 -1 (-8050 3500)(-8500 3500);
WIRE 16 -1 (-8500 3500)(-8500 3625);
WIRE 16 -1 (-8950 3500)(-8950 3625);
WIRE 16 -1 (-8950 3500)(-9400 3500);
WIRE 16 -1 (-9400 3500)(-9400 3625);
WIRE 16 -1 (-7600 3500)(-8050 3500);
WIRE 16 -1 (-8050 3500)(-8050 3625);
WIRE 16 -1 (-7150 3500)(-7600 3500);
WIRE 16 -1 (-7600 3500)(-7600 3625);
WIRE 16 -1 (-7150 3500)(-7150 3625);
WIRE 16 -1 (-6700 3500)(-7150 3500);
WIRE 16 -1 (-6250 3500)(-6700 3500);
WIRE 16 -1 (-6700 3500)(-6700 3625);
WIRE 16 -1 (-5800 3500)(-6250 3500);
WIRE 16 -1 (-6250 3500)(-6250 3625);
WIRE 16 -1 (-5800 3500)(-5400 3500);
WIRE 16 -1 (-5800 3500)(-5800 3625);
WIRE 16 -1 (-5400 3500)(-5400 3625);
WIRE 16 -1 (-5400 3400)(-5400 3500);
WIRE 16 -1 (-8050 4675)(-8500 4675);
WIRE 16 -1 (-7600 4675)(-8050 4675);
WIRE 16 -1 (-8050 4600)(-8050 4675);
WIRE 16 -1 (-8500 4675)(-8500 4600);
WIRE 16 -1 (-8500 4675)(-8950 4675);
WIRE 16 -1 (-8950 4600)(-8950 4675);
WIRE 16 -1 (-8950 4675)(-9400 4675);
WIRE 16 -1 (-7150 4675)(-7600 4675);
WIRE 16 -1 (-7600 4600)(-7600 4675);
WIRE 16 -1 (-6700 4675)(-7150 4675);
WIRE 16 -1 (-7150 4675)(-7150 4600);
WIRE 16 -1 (-9400 4675)(-9400 4725);
WIRE 16 -1 (-9400 4675)(-9400 4600);
WIRE 16 -1 (-6250 4675)(-6700 4675);
WIRE 16 -1 (-6700 4600)(-6700 4675);
WIRE 16 -1 (-5800 4675)(-6250 4675);
WIRE 16 -1 (-6250 4600)(-6250 4675);
WIRE 16 -1 (-5400 4675)(-5800 4675);
WIRE 16 -1 (-5800 4675)(-5800 4600);
WIRE 16 -1 (-5400 4600)(-5400 4675);
WIRE 16 -1 (-8500 4275)(-8950 4275);
WIRE 16 -1 (-8050 4275)(-8500 4275);
WIRE 16 -1 (-8500 4275)(-8500 4400);
WIRE 16 -1 (-8950 4275)(-8950 4400);
WIRE 16 -1 (-8950 4275)(-9400 4275);
WIRE 16 -1 (-9400 4275)(-9400 4400);
WIRE 16 -1 (-7600 4275)(-8050 4275);
WIRE 16 -1 (-8050 4275)(-8050 4400);
WIRE 16 -1 (-7150 4275)(-7600 4275);
WIRE 16 -1 (-7600 4275)(-7600 4400);
WIRE 16 -1 (-6700 4275)(-7150 4275);
WIRE 16 -1 (-7150 4275)(-7150 4400);
WIRE 16 -1 (-6250 4275)(-6700 4275);
WIRE 16 -1 (-6700 4275)(-6700 4400);
WIRE 16 -1 (-5800 4275)(-6250 4275);
WIRE 16 -1 (-6250 4275)(-6250 4400);
WIRE 16 -1 (-5400 4275)(-5800 4275);
WIRE 16 -1 (-5800 4275)(-5800 4400);
WIRE 16 -1 (-5400 4275)(-5400 4400);
WIRE 16 -1 (-5400 4175)(-5400 4275);
WIRE 16 3135 (-9625 5350)(-5100 5350);
WIRE 16 3135 (-9625 600)(-9625 5350);
WIRE 16 3135 (-5100 600)(-5100 5350);
WIRE 16 3135 (-9625 600)(-5100 600);
WIRE 16 -1 (-3925 1900)(-4375 1900);
WIRE 16 -1 (-3475 1900)(-3925 1900);
WIRE 16 -1 (-3925 1900)(-3925 2025);
WIRE 16 -1 (-4375 1900)(-4375 2025);
WIRE 16 -1 (-4375 1900)(-4825 1900);
WIRE 16 -1 (-4825 1900)(-4825 2025);
WIRE 16 -1 (-3025 1900)(-3475 1900);
WIRE 16 -1 (-3475 1900)(-3475 2025);
WIRE 16 -1 (-2575 1900)(-3025 1900);
WIRE 16 -1 (-3025 1900)(-3025 2025);
WIRE 16 -1 (-2125 1900)(-2575 1900);
WIRE 16 -1 (-2575 1900)(-2575 2025);
WIRE 16 -1 (-1675 1900)(-2125 1900);
WIRE 16 -1 (-2125 1900)(-2125 2025);
WIRE 16 -1 (-1225 1900)(-1675 1900);
WIRE 16 -1 (-1675 1900)(-1675 2025);
WIRE 16 -1 (-1225 1900)(-825 1900);
WIRE 16 -1 (-1225 1900)(-1225 2025);
WIRE 16 -1 (-825 1900)(-825 2025);
WIRE 16 -1 (-825 1800)(-825 1900);
WIRE 16 -1 (-3475 1500)(-3925 1500);
WIRE 16 -1 (-3025 1500)(-3475 1500);
WIRE 16 -1 (-3475 1425)(-3475 1500);
WIRE 16 -1 (-3925 1500)(-3925 1425);
WIRE 16 -1 (-3925 1500)(-4375 1500);
WIRE 16 -1 (-4375 1425)(-4375 1500);
WIRE 16 -1 (-4375 1500)(-4825 1500);
WIRE 16 -1 (-3025 1425)(-3025 1500);
WIRE 16 -1 (-4825 1500)(-4825 1550);
WIRE 16 -1 (-4825 1500)(-4825 1425);
WIRE 16 -1 (-3925 1100)(-4375 1100);
WIRE 16 -1 (-3475 1100)(-3925 1100);
WIRE 16 -1 (-3925 1100)(-3925 1225);
WIRE 16 -1 (-4375 1100)(-4375 1225);
WIRE 16 -1 (-4375 1100)(-4825 1100);
WIRE 16 -1 (-4825 1100)(-4825 1225);
WIRE 16 -1 (-3025 1100)(-3475 1100);
WIRE 16 -1 (-3475 1100)(-3475 1225);
WIRE 16 -1 (-3025 1100)(-3025 1225);
WIRE 16 -1 (-3025 1000)(-3025 1100);
WIRE 16 -1 (-3925 2700)(-4375 2700);
WIRE 16 -1 (-3475 2700)(-3925 2700);
WIRE 16 -1 (-3925 2700)(-3925 2825);
WIRE 16 -1 (-4375 2700)(-4375 2825);
WIRE 16 -1 (-4375 2700)(-4825 2700);
WIRE 16 -1 (-4825 2700)(-4825 2825);
WIRE 16 -1 (-3025 2700)(-3475 2700);
WIRE 16 -1 (-3475 2700)(-3475 2825);
WIRE 16 -1 (-2575 2700)(-3025 2700);
WIRE 16 -1 (-3025 2700)(-3025 2825);
WIRE 16 -1 (-2125 2700)(-2575 2700);
WIRE 16 -1 (-2575 2700)(-2575 2825);
WIRE 16 -1 (-1675 2700)(-2125 2700);
WIRE 16 -1 (-2125 2700)(-2125 2825);
WIRE 16 -1 (-1225 2700)(-1675 2700);
WIRE 16 -1 (-1675 2700)(-1675 2825);
WIRE 16 -1 (-1225 2700)(-825 2700);
WIRE 16 -1 (-1225 2700)(-1225 2825);
WIRE 16 -1 (-825 2700)(-825 2825);
WIRE 16 -1 (-825 2600)(-825 2700);
WIRE 16 -1 (-3475 2300)(-3925 2300);
WIRE 16 -1 (-3025 2300)(-3475 2300);
WIRE 16 -1 (-3475 2225)(-3475 2300);
WIRE 16 -1 (-3925 2300)(-3925 2225);
WIRE 16 -1 (-3925 2300)(-4375 2300);
WIRE 16 -1 (-4375 2225)(-4375 2300);
WIRE 16 -1 (-4375 2300)(-4825 2300);
WIRE 16 -1 (-2575 2300)(-3025 2300);
WIRE 16 -1 (-3025 2225)(-3025 2300);
WIRE 16 -1 (-2125 2300)(-2575 2300);
WIRE 16 -1 (-2575 2300)(-2575 2225);
WIRE 16 -1 (-4825 2300)(-4825 2350);
WIRE 16 -1 (-4825 2300)(-4825 2225);
WIRE 16 -1 (-1675 2300)(-2125 2300);
WIRE 16 -1 (-2125 2225)(-2125 2300);
WIRE 16 -1 (-1225 2300)(-1675 2300);
WIRE 16 -1 (-1675 2225)(-1675 2300);
WIRE 16 -1 (-825 2300)(-1225 2300);
WIRE 16 -1 (-1225 2300)(-1225 2225);
WIRE 16 -1 (-825 2225)(-825 2300);
WIRE 16 -1 (-3475 3900)(-3925 3900);
WIRE 16 -1 (-3025 3900)(-3475 3900);
WIRE 16 -1 (-3475 3825)(-3475 3900);
WIRE 16 -1 (-3925 3900)(-3925 3825);
WIRE 16 -1 (-3925 3900)(-4375 3900);
WIRE 16 -1 (-4375 3825)(-4375 3900);
WIRE 16 -1 (-4375 3900)(-4825 3900);
WIRE 16 -1 (-2575 3900)(-3025 3900);
WIRE 16 -1 (-3025 3825)(-3025 3900);
WIRE 16 -1 (-2125 3900)(-2575 3900);
WIRE 16 -1 (-2575 3900)(-2575 3825);
WIRE 16 -1 (-4825 3900)(-4825 3950);
WIRE 16 -1 (-4825 3900)(-4825 3825);
WIRE 16 -1 (-1675 3900)(-2125 3900);
WIRE 16 -1 (-2125 3825)(-2125 3900);
WIRE 16 -1 (-1225 3900)(-1675 3900);
WIRE 16 -1 (-1675 3825)(-1675 3900);
WIRE 16 -1 (-825 3900)(-1225 3900);
WIRE 16 -1 (-1225 3900)(-1225 3825);
WIRE 16 -1 (-825 3825)(-825 3900);
WIRE 16 -1 (-825 3500)(-825 3625);
WIRE 16 -1 (-825 3400)(-825 3500);
WIRE 16 -1 (-1225 3500)(-825 3500);
WIRE 16 -1 (-1225 3500)(-1225 3625);
WIRE 16 -1 (-1225 3500)(-1675 3500);
WIRE 16 -1 (-1675 3500)(-1675 3625);
WIRE 16 -1 (-1675 3500)(-2125 3500);
WIRE 16 -1 (-2125 3500)(-2125 3625);
WIRE 16 -1 (-2125 3500)(-2575 3500);
WIRE 16 -1 (-2575 3500)(-2575 3625);
WIRE 16 -1 (-2575 3500)(-3025 3500);
WIRE 16 -1 (-3025 3500)(-3025 3625);
WIRE 16 -1 (-3025 3500)(-3475 3500);
WIRE 16 -1 (-3475 3500)(-3475 3625);
WIRE 16 -1 (-3475 3500)(-3925 3500);
WIRE 16 -1 (-3925 3500)(-3925 3625);
WIRE 16 -1 (-3925 3500)(-4375 3500);
WIRE 16 -1 (-4375 3500)(-4375 3625);
WIRE 16 -1 (-4375 3500)(-4825 3500);
WIRE 16 -1 (-4825 3500)(-4825 3625);
WIRE 16 -1 (-825 3025)(-825 3100);
WIRE 16 -1 (-825 3100)(-1225 3100);
WIRE 16 -1 (-1225 3100)(-1675 3100);
WIRE 16 -1 (-1225 3100)(-1225 3025);
WIRE 16 -1 (-1675 3025)(-1675 3100);
WIRE 16 -1 (-1675 3100)(-2125 3100);
WIRE 16 -1 (-2125 3100)(-2575 3100);
WIRE 16 -1 (-2125 3025)(-2125 3100);
WIRE 16 -1 (-2575 3100)(-3025 3100);
WIRE 16 -1 (-2575 3100)(-2575 3025);
WIRE 16 -1 (-3025 3025)(-3025 3100);
WIRE 16 -1 (-3025 3100)(-3475 3100);
WIRE 16 -1 (-3475 3100)(-3925 3100);
WIRE 16 -1 (-3475 3025)(-3475 3100);
WIRE 16 -1 (-3925 3100)(-3925 3025);
WIRE 16 -1 (-3925 3100)(-4375 3100);
WIRE 16 -1 (-4375 3100)(-4825 3100);
WIRE 16 -1 (-4375 3025)(-4375 3100);
WIRE 16 -1 (-4825 3100)(-4825 3150);
WIRE 16 -1 (-4825 3100)(-4825 3025);
WIRE 16 -1 (-3475 4675)(-3925 4675);
WIRE 16 -1 (-3025 4675)(-3475 4675);
WIRE 16 -1 (-3475 4600)(-3475 4675);
WIRE 16 -1 (-3925 4675)(-3925 4600);
WIRE 16 -1 (-3925 4675)(-4375 4675);
WIRE 16 -1 (-4375 4600)(-4375 4675);
WIRE 16 -1 (-4375 4675)(-4825 4675);
WIRE 16 -1 (-2575 4675)(-3025 4675);
WIRE 16 -1 (-3025 4600)(-3025 4675);
WIRE 16 -1 (-2125 4675)(-2575 4675);
WIRE 16 -1 (-2575 4675)(-2575 4600);
WIRE 16 -1 (-4825 4675)(-4825 4725);
WIRE 16 -1 (-4825 4675)(-4825 4600);
WIRE 16 -1 (-1675 4675)(-2125 4675);
WIRE 16 -1 (-2125 4600)(-2125 4675);
WIRE 16 -1 (-1225 4675)(-1675 4675);
WIRE 16 -1 (-1675 4600)(-1675 4675);
WIRE 16 -1 (-825 4675)(-1225 4675);
WIRE 16 -1 (-1225 4675)(-1225 4600);
WIRE 16 -1 (-825 4600)(-825 4675);
WIRE 16 -1 (-3925 4275)(-4375 4275);
WIRE 16 -1 (-3475 4275)(-3925 4275);
WIRE 16 -1 (-3925 4275)(-3925 4400);
WIRE 16 -1 (-4375 4275)(-4375 4400);
WIRE 16 -1 (-4375 4275)(-4825 4275);
WIRE 16 -1 (-4825 4275)(-4825 4400);
WIRE 16 -1 (-3025 4275)(-3475 4275);
WIRE 16 -1 (-3475 4275)(-3475 4400);
WIRE 16 -1 (-2575 4275)(-3025 4275);
WIRE 16 -1 (-3025 4275)(-3025 4400);
WIRE 16 -1 (-2125 4275)(-2575 4275);
WIRE 16 -1 (-2575 4275)(-2575 4400);
WIRE 16 -1 (-1675 4275)(-2125 4275);
WIRE 16 -1 (-2125 4275)(-2125 4400);
WIRE 16 -1 (-1225 4275)(-1675 4275);
WIRE 16 -1 (-1675 4275)(-1675 4400);
WIRE 16 -1 (-825 4275)(-1225 4275);
WIRE 16 -1 (-1225 4275)(-1225 4400);
WIRE 16 -1 (-825 4275)(-825 4400);
WIRE 16 -1 (-825 4175)(-825 4275);
WIRE 16 3135 (-5000 5350)(-500 5350);
WIRE 16 3135 (-5000 600)(-5000 5350);
WIRE 16 3135 (-500 600)(-500 5350);
WIRE 16 3135 (-5000 600)(-500 600);
DOT 1 (-8500 3500);
DOT 1 (-8050 1900);
DOT 1 (-9400 1500);
DOT 1 (-8950 1100);
DOT 1 (-8950 1500);
DOT 1 (-8500 1100);
DOT 1 (-8500 1500);
DOT 1 (-9400 2300);
DOT 1 (-9400 3100);
DOT 1 (-8950 1900);
DOT 1 (-8950 2300);
DOT 1 (-8500 1900);
DOT 1 (-8500 2300);
DOT 1 (-8950 2700);
DOT 1 (-8950 3100);
DOT 1 (-8950 3500);
DOT 1 (-8500 2700);
DOT 1 (-8500 3100);
DOT 1 (-9400 3900);
DOT 1 (-9400 4675);
DOT 1 (-8950 3900);
DOT 1 (-8950 4275);
DOT 1 (-8950 4675);
DOT 1 (-8500 3900);
DOT 1 (-8500 4275);
DOT 1 (-8500 4675);
DOT 1 (-8050 1100);
DOT 1 (-8050 1500);
DOT 1 (-7600 1100);
DOT 1 (-8050 2300);
DOT 1 (-7600 1900);
DOT 1 (-7150 1900);
DOT 1 (-7600 2300);
DOT 1 (-7150 2300);
DOT 1 (-8050 2700);
DOT 1 (-8050 3100);
DOT 1 (-8050 3500);
DOT 1 (-7600 2700);
DOT 1 (-7600 3100);
DOT 1 (-7150 2700);
DOT 1 (-7150 3100);
DOT 1 (-7600 3500);
DOT 1 (-7150 3500);
DOT 1 (-6700 1900);
DOT 1 (-6700 2300);
DOT 1 (-6250 1900);
DOT 1 (-6250 2300);
DOT 1 (-6700 2700);
DOT 1 (-6700 3100);
DOT 1 (-6700 3500);
DOT 1 (-6250 2700);
DOT 1 (-6250 3100);
DOT 1 (-6250 3500);
DOT 1 (-4825 1500);
DOT 1 (-4375 1100);
DOT 1 (-4375 1500);
DOT 1 (-5800 1900);
DOT 1 (-5800 2300);
DOT 1 (-5400 1900);
DOT 1 (-5800 2700);
DOT 1 (-5800 3100);
DOT 1 (-5800 3500);
DOT 1 (-5400 2700);
DOT 1 (-5400 3500);
DOT 1 (-4825 2300);
DOT 1 (-4375 1900);
DOT 1 (-4375 2300);
DOT 1 (-4825 3100);
DOT 1 (-4375 2700);
DOT 1 (-4375 3100);
DOT 1 (-4375 3500);
DOT 1 (-8050 3900);
DOT 1 (-8050 4275);
DOT 1 (-8050 4675);
DOT 1 (-7600 3900);
DOT 1 (-7150 3900);
DOT 1 (-7600 4275);
DOT 1 (-7600 4675);
DOT 1 (-7150 4275);
DOT 1 (-7150 4675);
DOT 1 (-6700 3900);
DOT 1 (-6700 4275);
DOT 1 (-6700 4675);
DOT 1 (-6250 3900);
DOT 1 (-6250 4275);
DOT 1 (-6250 4675);
DOT 1 (-5800 3900);
DOT 1 (-5800 4275);
DOT 1 (-5800 4675);
DOT 1 (-5400 4275);
DOT 1 (-4825 3900);
DOT 1 (-4825 4675);
DOT 1 (-4375 3900);
DOT 1 (-4375 4275);
DOT 1 (-3925 1100);
DOT 1 (-3925 1500);
DOT 1 (-3475 1100);
DOT 1 (-3475 1500);
DOT 1 (-3025 1100);
DOT 1 (-3925 1900);
DOT 1 (-3925 2300);
DOT 1 (-3475 1900);
DOT 1 (-3475 2300);
DOT 1 (-3925 2700);
DOT 1 (-3925 3100);
DOT 1 (-3925 3500);
DOT 1 (-3475 2700);
DOT 1 (-3475 3100);
DOT 1 (-3475 3500);
DOT 1 (-3025 1900);
DOT 1 (-2575 1900);
DOT 1 (-3025 2300);
DOT 1 (-2575 2300);
DOT 1 (-2125 1900);
DOT 1 (-2125 2300);
DOT 1 (-3025 2700);
DOT 1 (-3025 3100);
DOT 1 (-2575 2700);
DOT 1 (-2575 3100);
DOT 1 (-3025 3500);
DOT 1 (-2575 3500);
DOT 1 (-2125 2700);
DOT 1 (-2125 3100);
DOT 1 (-2125 3500);
DOT 1 (-1675 1900);
DOT 1 (-1675 2300);
DOT 1 (-1225 1900);
DOT 1 (-1225 2300);
DOT 1 (-1675 2700);
DOT 1 (-1675 3100);
DOT 1 (-1675 3500);
DOT 1 (-1225 2700);
DOT 1 (-1225 3100);
DOT 1 (-1225 3500);
DOT 1 (-825 1900);
DOT 1 (-825 2700);
DOT 1 (-825 3500);
DOT 1 (-3925 3900);
DOT 1 (-3925 4275);
DOT 1 (-3925 4675);
DOT 1 (-3475 3900);
DOT 1 (-3475 4275);
DOT 1 (-3475 4675);
DOT 1 (-3025 3900);
DOT 1 (-2575 3900);
DOT 1 (-3025 4275);
DOT 1 (-3025 4675);
DOT 1 (-2575 4275);
DOT 1 (-2575 4675);
DOT 1 (-2125 3900);
DOT 1 (-2125 4275);
DOT 1 (-2125 4675);
DOT 1 (-1675 3900);
DOT 1 (-1675 4275);
DOT 1 (-1675 4675);
DOT 1 (-1225 3900);
DOT 1 (-1225 4275);
DOT 1 (-1225 4675);
DOT 1 (-825 4275);
DOT 1 (-4375 4675);
FORCENOTE
PVDDCR_CPU0_P1: 45PCS 22UF ON BOT
(-9525 5075) 0;
DISPLAY LEFT (-9525 5075);
DISPLAY 2.510638 (-9525 5075);
PAINT WHITE (-9525 5075);
FORCENOTE
5
(-7600 1550) 0;
DISPLAY LEFT (-7600 1550);
DISPLAY 1.021277 (-7600 1550);
PAINT SKYBLUE (-7600 1550);
FORCENOTE
5
(-7625 4775) 0;
DISPLAY LEFT (-7625 4775);
DISPLAY 1.021277 (-7625 4775);
PAINT SKYBLUE (-7625 4775);
FORCENOTE
10
(-5450 4775) 0;
DISPLAY LEFT (-5450 4775);
DISPLAY 1.021277 (-5450 4775);
PAINT SKYBLUE (-5450 4775);
FORCENOTE
5
(-3025 1575) 0;
DISPLAY LEFT (-3025 1575);
DISPLAY 1.021277 (-3025 1575);
PAINT SKYBLUE (-3025 1575);
FORCENOTE
5
(-3050 4800) 0;
DISPLAY LEFT (-3050 4800);
DISPLAY 1.021277 (-3050 4800);
PAINT SKYBLUE (-3050 4800);
FORCENOTE
10
(-875 4775) 0;
DISPLAY LEFT (-875 4775);
DISPLAY 1.021277 (-875 4775);
PAINT SKYBLUE (-875 4775);
FORCENOTE
PVDDCR_CPU1_P1: 45PCS 22UF ON BOT
(-4875 5100) 0;
DISPLAY LEFT (-4875 5100);
DISPLAY 2.510638 (-4875 5100);
PAINT WHITE (-4875 5100);
QUIT
